.HEADER
BOARD_FILE 3.0 "Creo Elements/Pro 5.0 M210" 2017/06/07.10:09:58 3
16315-1                                 MM        
.END_HEADER
.BOARD_OUTLINE  MCAD
2.36000             
         0           490.45000           349.20000             0.00000
         0           296.70000           349.20000             0.00000
         0           295.70000           350.20000           -90.00000
         0           295.70000           373.00000             0.00000
         0           296.70000           374.00000           -90.00000
         0           309.00000           374.00000             0.00000
         0           310.00000           375.00000            90.00000
         0           310.00000           420.20000             0.00000
         0           309.00000           421.20000            90.00000
         0           201.00000           421.20000             0.00000
         0           200.00000           420.20000            90.00000
         0           200.00000           374.00000             0.00000
         0           199.00000           373.00000           -90.00000
         0           191.70000           373.00000             0.00000
         0           190.70000           372.00000            90.00000
         0           190.70000           350.20000             0.00000
         0           189.70000           349.20000           -90.00000
         0             1.00000           349.20000             0.00000
         0             0.00000           348.20000            90.00000
         0             0.00000             1.00000             0.00000
         0             1.00000             0.00000            90.00000
         0           101.00000            -0.00000             0.00000
         0           102.00000             1.00000            90.00000
         0           102.00000            14.00000             0.00000
         0           103.00000            15.00000           -90.00000
         0           149.00000            15.00000             0.00000
         0           150.00000            14.00000           -90.00000
         0           150.00000             1.00000             0.00000
         0           151.00000             0.00000            90.00000
         0           199.00000             0.00000             0.00000
         0           200.00000            -1.00000           -90.00000
         0           201.00000            -2.00000            90.00000
         0           219.00000            -2.00000             0.00000
         0           220.00000            -3.00000           -90.00000
         0           220.00000           -37.80000             0.00000
         0           221.00000           -38.80000            90.00000
         0           299.00000           -38.80000             0.00000
         0           300.00000           -37.80000            90.00000
         0           300.00000            -1.00000             0.00000
         0           301.00000             0.00000           -90.00000
         0           347.00000            -0.00000             0.00000
         0           348.00000             1.00000            90.00000
         0           348.00000            14.00000             0.00000
         0           349.00000            15.00000           -90.00000
         0           395.00000            15.00000             0.00000
         0           396.00000            14.00000           -90.00000
         0           396.00000             1.00000             0.00000
         0           397.00000             0.00000            90.00000
         0           490.45000            -0.00000             0.00000
         0           491.45000             1.00000            90.00000
         0           491.45000           348.20000             0.00000
         0           490.45000           349.20000            90.00000
         1            29.03103            96.23683             0.00000
         1            30.78997            99.57209            21.73429
         1            35.86003            99.57209          -146.12196
         1            37.61897            96.23683            21.73429
         1            29.03103            96.23683          -257.34662
         2            92.03103            96.23683             0.00000
         2            93.78997            99.57209            21.73429
         2            98.86003            99.57209          -146.12196
         2           100.61897            96.23683            21.73429
         2            92.03103            96.23683          -257.34662
         3           155.03103            96.23683             0.00000
         3           156.78997            99.57209            21.73429
         3           161.86003            99.57209          -146.12196
         3           163.61897            96.23683            21.73429
         3           155.03103            96.23683          -257.34662
         4            29.03103           211.23683             0.00000
         4            30.78997           214.57209            21.73429
         4            35.86003           214.57209          -146.12196
         4            37.61897           211.23683            21.73429
         4            29.03103           211.23683          -257.34662
         5            92.03103           211.23683             0.00000
         5            93.78997           214.57209            21.73429
         5            98.86003           214.57209          -146.12196
         5           100.61897           211.23683            21.73429
         5            92.03103           211.23683          -257.34662
         6           155.03103           211.23683             0.00000
         6           156.78997           214.57209            21.73429
         6           161.86003           214.57209          -146.12196
         6           163.61897           211.23683            21.73429
         6           155.03103           211.23683          -257.34662
         7            29.03103           326.23683             0.00000
         7            30.78997           329.57209            21.73429
         7            35.86003           329.57209          -146.12196
         7            37.61897           326.23683            21.73429
         7            29.03103           326.23683          -257.34662
         8            92.03103           326.23683             0.00000
         8            93.78997           329.57209            21.73429
         8            98.86003           329.57209          -146.12196
         8           100.61897           326.23683            21.73429
         8            92.03103           326.23683          -257.34662
         9           155.03103           326.23683             0.00000
         9           156.78997           329.57209            21.73429
         9           161.86003           329.57209          -146.12196
         9           163.61897           326.23683            21.73429
         9           155.03103           326.23683          -257.34662
        10           326.38103            96.23683             0.00000
        10           328.13997            99.57209            21.73429
        10           333.21003            99.57209          -146.12196
        10           334.96897            96.23683            21.73429
        10           326.38103            96.23683          -257.34662
        11           389.38103            96.23683             0.00000
        11           391.13997            99.57209            21.73429
        11           396.21003            99.57209          -146.12196
        11           397.96897            96.23683            21.73429
        11           389.38103            96.23683          -257.34662
        12           452.38103            96.23683             0.00000
        12           454.13997            99.57209            21.73429
        12           459.21003            99.57209          -146.12196
        12           460.96897            96.23683            21.73429
        12           452.38103            96.23683          -257.34662
        13           326.38103           211.23683             0.00000
        13           328.13997           214.57209            21.73429
        13           333.21003           214.57209          -146.12196
        13           334.96897           211.23683            21.73429
        13           326.38103           211.23683          -257.34662
        14           389.38103           211.23683             0.00000
        14           391.13997           214.57209            21.73429
        14           396.21003           214.57209          -146.12196
        14           397.96897           211.23683            21.73429
        14           389.38103           211.23683          -257.34662
        15           452.38103           211.23683             0.00000
        15           454.13997           214.57209            21.73429
        15           459.21003           214.57209          -146.12196
        15           460.96897           211.23683            21.73429
        15           452.38103           211.23683          -257.34662
        16           326.38103           326.23683             0.00000
        16           328.13997           329.57209            21.73429
        16           333.21003           329.57209          -146.12196
        16           334.96897           326.23683            21.73429
        16           326.38103           326.23683          -257.34662
        17           389.38103           326.23683             0.00000
        17           391.13997           329.57209            21.73429
        17           396.21003           329.57209          -146.12196
        17           397.96897           326.23683            21.73429
        17           389.38103           326.23683          -257.34662
        18           452.38103           326.23683             0.00000
        18           454.13997           329.57209            21.73429
        18           459.21003           329.57209          -146.12196
        18           460.96897           326.23683            21.73429
        18           452.38103           326.23683          -257.34662
        19           198.00603           187.23683             0.00000
        19           199.76497           190.57209            21.73429
        19           204.83503           190.57209          -146.12196
        19           206.59397           187.23683            21.73429
        19           198.00603           187.23683          -257.34662
        20           295.90603           246.63683             0.00000
        20           297.66497           249.97209            21.73429
        20           302.73503           249.97209          -146.12196
        20           304.49397           246.63683            21.73429
        20           295.90603           246.63683          -257.34662
        21           239.90603           276.63683             0.00000
        21           241.66497           279.97209            21.73429
        21           246.73503           279.97209          -146.12196
        21           248.49397           276.63683            21.73429
        21           239.90603           276.63683          -257.34662
        22           295.90603           396.63683             0.00000
        22           297.66497           399.97209            21.73429
        22           302.73503           399.97209          -146.12196
        22           304.49397           396.63683            21.73429
        22           295.90603           396.63683          -257.34662
        23           239.90603           363.63683             0.00000
        23           241.66497           366.97209            21.73429
        23           246.73503           366.97209          -146.12196
        23           248.49397           363.63683            21.73429
        23           239.90603           363.63683          -257.34662
        24           198.00603            67.23683             0.00000
        24           199.76497            70.57209            21.73429
        24           204.83503            70.57209          -146.12196
        24           206.59397            67.23683            21.73429
        24           198.00603            67.23683          -257.34662
        25           295.90603           141.63683             0.00000
        25           297.66497           144.97209            21.73429
        25           302.73503           144.97209          -146.12196
        25           304.49397           141.63683            21.73429
        25           295.90603           141.63683          -257.34662
        26           420.02500           210.80000             0.00000
        26           430.32500           210.80000          -180.00000
        26           420.02500           210.80000          -180.00000
        27           122.67500           210.80000             0.00000
        27           132.97500           210.80000          -180.00000
        27           122.67500           210.80000          -180.00000
        28           479.15000             5.50000             0.00000
        28           483.35000             5.50000          -180.00000
        28           479.15000             5.50000          -180.00000
        29             1.75000             5.50000             0.00000
        29             5.95000             5.50000          -180.00000
        29             1.75000             5.50000          -180.00000
        30           246.35000           143.50000             0.00000
        30           249.35000           143.50000          -180.00000
        30           246.35000           143.50000          -180.00000
        31           227.75000           143.50000             0.00000
        31           231.95000           143.50000          -180.00000
        31           227.75000           143.50000          -180.00000
        32           370.94500            20.55000             0.00000
        32           373.35500            20.55000          -180.00000
        32           370.94500            20.55000          -180.00000
        33           370.87500            28.08000             0.00000
        33           373.42500            28.08000          -180.00000
        33           370.87500            28.08000          -180.00000
        34           124.94500            20.55000             0.00000
        34           127.35500            20.55000          -180.00000
        34           124.94500            20.55000          -180.00000
        35           124.87500            28.08000             0.00000
        35           127.42500            28.08000          -180.00000
        35           124.87500            28.08000          -180.00000
        36            42.22500           270.00000             0.00000
        36            45.77500           270.00000          -180.00000
        36            42.22500           270.00000          -180.00000
        37           105.32500           290.00000             0.00000
        37           108.87500           290.00000          -180.00000
        37           105.32500           290.00000          -180.00000
        38           168.42500           270.00000             0.00000
        38           171.97500           270.00000          -180.00000
        38           168.42500           270.00000          -180.00000
        39           339.52500           270.00000             0.00000
        39           343.07500           270.00000          -180.00000
        39           339.52500           270.00000          -180.00000
        40           402.62500           290.00000             0.00000
        40           406.17500           290.00000          -180.00000
        40           402.62500           290.00000          -180.00000
        41           465.72500           270.00000             0.00000
        41           469.27500           270.00000          -180.00000
        41           465.72500           270.00000          -180.00000
        42           466.10000           283.00000             0.00000
        42           468.90000           283.00000          -180.00000
        42           466.10000           283.00000          -180.00000
        43           339.90000           283.00000             0.00000
        43           342.70000           283.00000          -180.00000
        43           339.90000           283.00000          -180.00000
        44           168.80000           283.00000             0.00000
        44           171.60000           283.00000          -180.00000
        44           168.80000           283.00000          -180.00000
        45            42.60000           283.00000             0.00000
        45            45.40000           283.00000          -180.00000
        45            42.60000           283.00000          -180.00000
        46           320.82500             9.20000             0.00000
        46           326.52500             9.20000          -180.00000
        46           320.82500             9.20000          -180.00000
        47           460.82500             9.20000             0.00000
        47           466.52500             9.20000          -180.00000
        47           460.82500             9.20000          -180.00000
        48            23.47500             9.20000             0.00000
        48            29.17500             9.20000          -180.00000
        48            23.47500             9.20000          -180.00000
        49           163.47500             9.20000             0.00000
        49           169.17500             9.20000          -180.00000
        49           163.47500             9.20000          -180.00000
        50           316.57500            13.20000             0.00000
        50           318.77500            13.20000          -180.00000
        50           316.57500            13.20000          -180.00000
        51           328.57500             5.20000             0.00000
        51           330.77500             5.20000          -180.00000
        51           328.57500             5.20000          -180.00000
        52           456.57500            13.20000             0.00000
        52           458.77500            13.20000          -180.00000
        52           456.57500            13.20000          -180.00000
        53           468.57500             5.20000             0.00000
        53           470.77500             5.20000          -180.00000
        53           468.57500             5.20000          -180.00000
        54           171.22500             5.20000             0.00000
        54           173.42500             5.20000          -180.00000
        54           171.22500             5.20000          -180.00000
        55           159.22500            13.20000             0.00000
        55           161.42500            13.20000          -180.00000
        55           159.22500            13.20000          -180.00000
        56            19.22500            13.20000             0.00000
        56            21.42500            13.20000          -180.00000
        56            19.22500            13.20000          -180.00000
        57            31.22500             5.20000             0.00000
        57            33.42500             5.20000          -180.00000
        57            31.22500             5.20000          -180.00000
        58           282.30000           414.22000             0.00000
        58           278.80000           414.22000          -180.00000
        58           282.30000           414.22000          -180.00000
        59            10.10000           224.20000             0.00000
        59             5.90000           224.20000          -180.00000
        59            10.10000           224.20000          -180.00000
        60           485.55000           204.20000             0.00000
        60           481.35000           204.20000          -180.00000
        60           485.55000           204.20000          -180.00000
        61           227.75000            -5.50000             0.00000
        61           231.95000            -5.50000          -180.00000
        61           231.95000            -7.50000             0.00000
        61           227.75000            -7.50000          -180.00000
        61           227.75000            -5.50000             0.00000
        62           483.35000           121.50000             0.00000
        62           483.35000           119.50000             0.00000
        62           479.15000           119.50000          -180.00000
        62           479.15000           121.50000             0.00000
        62           483.35000           121.50000          -180.00000
        63             5.95000           121.50000             0.00000
        63             5.95000           119.50000             0.00000
        63             1.75000           119.50000          -180.00000
        63             1.75000           121.50000             0.00000
        63             5.95000           121.50000          -180.00000
        64           249.35000            -5.50000             0.00000
        64           249.35000            -7.50000             0.00000
        64           246.35000            -7.50000          -180.00000
        64           246.35000            -5.50000             0.00000
        64           249.35000            -5.50000          -180.00000
        65            44.85000           164.20000             0.00000
        65            40.65000           164.20000          -180.00000
        65            44.85000           164.20000          -180.00000
        66           169.80000           164.20000             0.00000
        66           165.60000           164.20000          -180.00000
        66           169.80000           164.20000          -180.00000
        67           349.10000           164.20000             0.00000
        67           344.90000           164.20000          -180.00000
        67           349.10000           164.20000          -180.00000
        68           409.20000           164.20000             0.00000
        68           405.00000           164.20000          -180.00000
        68           409.20000           164.20000          -180.00000
        69           244.53384           -14.68643             0.00000
        69           235.46616           -14.68643          -248.95783
        69           237.54064           -10.81305            12.61312
        69           242.45936           -10.81305          -136.26841
        69           244.53384           -14.68643            12.61312
        70           184.50000           208.50000             0.00000
        70           180.30000           208.50000          -180.00000
        70           184.50000           208.50000          -180.00000
        71           373.70000           220.20000             0.00000
        71           369.50000           220.20000          -180.00000
        71           373.70000           220.20000          -180.00000
.END_BOARD_OUTLINE
.DRILLED_HOLES
.END_DRILLED_HOLES
.PLACE_KEEPOUT      UNOWNED
TOP 0.00000        
         0           209.30000            69.80000             0.00000
         0           195.30000            69.80000           180.00000
         0           195.30000            63.80000             0.00000
         0           209.30000            63.80000           180.00000
         0           209.30000            69.80000             0.00000
.END_PLACE_KEEPOUT
.PLACE_KEEPOUT      UNOWNED
TOP 0.00000        
         0           166.32500            92.80000             0.00000
         0           166.32500            98.80000             0.00000
         0           152.32500            98.80000           180.00000
         0           152.32500            92.80000             0.00000
         0           166.32500            92.80000           180.00000
.END_PLACE_KEEPOUT
.PLACE_KEEPOUT      UNOWNED
TOP 0.00000        
         0           103.32500            98.80000             0.00000
         0            89.32500            98.80000           180.00000
         0            89.32500            92.80000             0.00000
         0           103.32500            92.80000           180.00000
         0           103.32500            98.80000             0.00000
.END_PLACE_KEEPOUT
.PLACE_KEEPOUT      UNOWNED
TOP 0.00000        
         0            40.32500            98.80000             0.00000
         0            26.32500            98.80000           180.00000
         0            26.32500            92.80000             0.00000
         0            40.32500            92.80000           180.00000
         0            40.32500            98.80000             0.00000
.END_PLACE_KEEPOUT
.PLACE_KEEPOUT      UNOWNED
TOP 0.00000        
         0           463.67500            92.80000             0.00000
         0           463.67500            98.80000             0.00000
         0           449.67500            98.80000           180.00000
         0           449.67500            92.80000             0.00000
         0           463.67500            92.80000           180.00000
.END_PLACE_KEEPOUT
.PLACE_KEEPOUT      UNOWNED
TOP 0.00000        
         0           400.67500            92.80000             0.00000
         0           400.67500            98.80000             0.00000
         0           386.67500            98.80000           180.00000
         0           386.67500            92.80000             0.00000
         0           400.67500            92.80000           180.00000
.END_PLACE_KEEPOUT
.PLACE_KEEPOUT      UNOWNED
TOP 0.00000        
         0           337.67500            92.80000             0.00000
         0           337.67500            98.80000             0.00000
         0           323.67500            98.80000           180.00000
         0           323.67500            92.80000             0.00000
         0           337.67500            92.80000           180.00000
.END_PLACE_KEEPOUT
.PLACE_KEEPOUT      UNOWNED
TOP 0.00000        
         0           307.20000           138.20000             0.00000
         0           307.20000           144.20000             0.00000
         0           293.20000           144.20000           180.00000
         0           293.20000           138.20000             0.00000
         0           307.20000           138.20000           180.00000
.END_PLACE_KEEPOUT
.PLACE_KEEPOUT      UNOWNED
TOP 0.00000        
         0           209.30000           189.80000             0.00000
         0           195.30000           189.80000           180.00000
         0           195.30000           183.80000             0.00000
         0           209.30000           183.80000           180.00000
         0           209.30000           189.80000             0.00000
.END_PLACE_KEEPOUT
.PLACE_KEEPOUT      UNOWNED
TOP 0.00000        
         0           166.32500           207.80000             0.00000
         0           166.32500           213.80000             0.00000
         0           152.32500           213.80000           180.00000
         0           152.32500           207.80000             0.00000
         0           166.32500           207.80000           180.00000
.END_PLACE_KEEPOUT
.PLACE_KEEPOUT      UNOWNED
TOP 0.00000        
         0           103.32500           207.80000             0.00000
         0           103.32500           213.80000             0.00000
         0            89.32500           213.80000           180.00000
         0            89.32500           207.80000             0.00000
         0           103.32500           207.80000           180.00000
.END_PLACE_KEEPOUT
.PLACE_KEEPOUT      UNOWNED
TOP 0.00000        
         0            40.32500           207.80000             0.00000
         0            40.32500           213.80000             0.00000
         0            26.32500           213.80000           180.00000
         0            26.32500           207.80000             0.00000
         0            40.32500           207.80000           180.00000
.END_PLACE_KEEPOUT
.PLACE_KEEPOUT      UNOWNED
TOP 0.00000        
         0           337.67500           207.80000             0.00000
         0           337.67500           213.80000             0.00000
         0           323.67500           213.80000           180.00000
         0           323.67500           207.80000             0.00000
         0           337.67500           207.80000           180.00000
.END_PLACE_KEEPOUT
.PLACE_KEEPOUT      UNOWNED
TOP 0.00000        
         0           307.20000           249.20000             0.00000
         0           293.20000           249.20000           180.00000
         0           293.20000           243.20000             0.00000
         0           307.20000           243.20000           180.00000
         0           307.20000           249.20000             0.00000
.END_PLACE_KEEPOUT
.PLACE_KEEPOUT      UNOWNED
TOP 0.00000        
         0           463.67500           207.80000             0.00000
         0           463.67500           213.80000             0.00000
         0           449.67500           213.80000           180.00000
         0           449.67500           207.80000             0.00000
         0           463.67500           207.80000           180.00000
.END_PLACE_KEEPOUT
.PLACE_KEEPOUT      UNOWNED
TOP 0.00000        
         0           400.67500           207.80000             0.00000
         0           400.67500           213.80000             0.00000
         0           386.67500           213.80000           180.00000
         0           386.67500           207.80000             0.00000
         0           400.67500           207.80000           180.00000
.END_PLACE_KEEPOUT
.PLACE_KEEPOUT      UNOWNED
TOP 0.00000        
         0           251.20000           279.20000             0.00000
         0           237.20000           279.20000           180.00000
         0           237.20000           273.20000             0.00000
         0           251.20000           273.20000           180.00000
         0           251.20000           279.20000             0.00000
.END_PLACE_KEEPOUT
.PLACE_KEEPOUT      UNOWNED
TOP 0.00000        
         0           166.32500           322.80000             0.00000
         0           166.32500           328.80000             0.00000
         0           152.32500           328.80000           180.00000
         0           152.32500           322.80000             0.00000
         0           166.32500           322.80000           180.00000
.END_PLACE_KEEPOUT
.PLACE_KEEPOUT      UNOWNED
TOP 0.00000        
         0           103.32500           322.80000             0.00000
         0           103.32500           328.80000             0.00000
         0            89.32500           328.80000           180.00000
         0            89.32500           322.80000             0.00000
         0           103.32500           322.80000           180.00000
.END_PLACE_KEEPOUT
.PLACE_KEEPOUT      UNOWNED
TOP 0.00000        
         0            40.32500           322.80000             0.00000
         0            40.32500           328.80000             0.00000
         0            26.32500           328.80000           180.00000
         0            26.32500           322.80000             0.00000
         0            40.32500           322.80000           180.00000
.END_PLACE_KEEPOUT
.PLACE_KEEPOUT      UNOWNED
TOP 0.00000        
         0           251.20000           360.20000             0.00000
         0           251.20000           366.20000             0.00000
         0           237.20000           366.20000           180.00000
         0           237.20000           360.20000             0.00000
         0           251.20000           360.20000           180.00000
.END_PLACE_KEEPOUT
.PLACE_KEEPOUT      UNOWNED
TOP 0.00000        
         0           307.20000           393.20000             0.00000
         0           307.20000           399.20000             0.00000
         0           293.20000           399.20000           180.00000
         0           293.20000           393.20000             0.00000
         0           307.20000           393.20000           180.00000
.END_PLACE_KEEPOUT
.PLACE_KEEPOUT      UNOWNED
TOP 0.00000        
         0           337.67500           322.80000             0.00000
         0           337.67500           328.80000             0.00000
         0           323.67500           328.80000           180.00000
         0           323.67500           322.80000             0.00000
         0           337.67500           322.80000           180.00000
.END_PLACE_KEEPOUT
.PLACE_KEEPOUT      UNOWNED
TOP 0.00000        
         0           400.67500           322.80000             0.00000
         0           400.67500           328.80000             0.00000
         0           386.67500           328.80000           180.00000
         0           386.67500           322.80000             0.00000
         0           400.67500           322.80000           180.00000
.END_PLACE_KEEPOUT
.PLACE_KEEPOUT      UNOWNED
TOP 0.00000        
         0           463.67500           322.80000             0.00000
         0           463.67500           328.80000             0.00000
         0           449.67500           328.80000           180.00000
         0           449.67500           322.80000             0.00000
         0           463.67500           322.80000           180.00000
.END_PLACE_KEEPOUT
.PLACE_KEEPOUT      UNOWNED
TOP 0.00000        
         0           367.85000           220.20000             0.00000
         0           375.35000           220.20000           180.00000
         0           367.85000           220.20000           180.00000
.END_PLACE_KEEPOUT
.PLACE_KEEPOUT      UNOWNED
TOP 0.00000        
         0           178.65000           208.50000             0.00000
         0           186.15000           208.50000           180.00000
         0           178.65000           208.50000           180.00000
.END_PLACE_KEEPOUT
.PLACE_KEEPOUT      UNOWNED
TOP 0.00000        
         0           477.50000             5.50000             0.00000
         0           485.00000             5.50000           180.00000
         0           477.50000             5.50000           180.00000
.END_PLACE_KEEPOUT
.PLACE_KEEPOUT      UNOWNED
TOP 0.00000        
         0           477.50000           120.50000             0.00000
         0           485.00000           120.50000           180.00000
         0           477.50000           120.50000           180.00000
.END_PLACE_KEEPOUT
.PLACE_KEEPOUT      UNOWNED
TOP 0.00000        
         0           244.10000            -6.50000             0.00000
         0           251.60000            -6.50000           180.00000
         0           244.10000            -6.50000           180.00000
.END_PLACE_KEEPOUT
.PLACE_KEEPOUT      UNOWNED
TOP 0.00000        
         0           244.10000           143.50000             0.00000
         0           251.60000           143.50000           180.00000
         0           244.10000           143.50000           180.00000
.END_PLACE_KEEPOUT
.PLACE_KEEPOUT      UNOWNED
TOP 0.00000        
         0             0.10000             5.50000             0.00000
         0             7.60000             5.50000           180.00000
         0             0.10000             5.50000           180.00000
.END_PLACE_KEEPOUT
.PLACE_KEEPOUT      UNOWNED
TOP 0.00000        
         0             0.10000           120.50000             0.00000
         0             7.60000           120.50000           180.00000
         0             0.10000           120.50000           180.00000
.END_PLACE_KEEPOUT
.PLACE_KEEPOUT      UNOWNED
TOP 0.00000        
         0           233.60000            -6.50000             0.00000
         0           226.10000            -6.50000           180.00000
         0           233.60000            -6.50000           180.00000
.END_PLACE_KEEPOUT
.PLACE_KEEPOUT      UNOWNED
TOP 0.00000        
         0           375.15000            28.08000             0.00000
         0           369.15000            28.08000           180.00000
         0           375.15000            28.08000           180.00000
.END_PLACE_KEEPOUT
.PLACE_KEEPOUT      UNOWNED
TOP 0.00000        
         0           129.15000            28.08000             0.00000
         0           123.15000            28.08000           180.00000
         0           129.15000            28.08000           180.00000
.END_PLACE_KEEPOUT
.PLACE_KEEPOUT      UNOWNED
TOP 0.00000        
         0           165.45000           270.00000             0.00000
         0           174.95000           270.00000           180.00000
         0           165.45000           270.00000           180.00000
.END_PLACE_KEEPOUT
.PLACE_KEEPOUT      UNOWNED
TOP 0.00000        
         0           102.35000           290.00000             0.00000
         0           111.85000           290.00000           180.00000
         0           102.35000           290.00000           180.00000
.END_PLACE_KEEPOUT
.PLACE_KEEPOUT      UNOWNED
TOP 0.00000        
         0            39.25000           270.00000             0.00000
         0            48.75000           270.00000           180.00000
         0            39.25000           270.00000           180.00000
.END_PLACE_KEEPOUT
.PLACE_KEEPOUT      UNOWNED
TOP 0.00000        
         0           336.55000           270.00000             0.00000
         0           346.05000           270.00000           180.00000
         0           336.55000           270.00000           180.00000
.END_PLACE_KEEPOUT
.PLACE_KEEPOUT      UNOWNED
TOP 0.00000        
         0           399.65000           290.00000             0.00000
         0           409.15000           290.00000           180.00000
         0           399.65000           290.00000           180.00000
.END_PLACE_KEEPOUT
.PLACE_KEEPOUT      UNOWNED
TOP 0.00000        
         0           462.75000           270.00000             0.00000
         0           472.25000           270.00000           180.00000
         0           462.75000           270.00000           180.00000
.END_PLACE_KEEPOUT
.PLACE_KEEPOUT      UNOWNED
TOP 0.00000        
         0           233.60000           143.50000             0.00000
         0           226.10000           143.50000           180.00000
         0           233.60000           143.50000           180.00000
.END_PLACE_KEEPOUT
.PLACE_KEEPOUT      UNOWNED
TOP 0.00000        
         0           284.30000           414.22000             0.00000
         0           276.80000           414.22000           180.00000
         0           284.30000           414.22000           180.00000
.END_PLACE_KEEPOUT
.PLACE_KEEPOUT      UNOWNED
TOP 0.00000        
         0           411.17500           210.80000             0.00000
         0           439.17500           210.80000           180.00000
         0           411.17500           210.80000           180.00000
.END_PLACE_KEEPOUT
.PLACE_KEEPOUT      UNOWNED
TOP 0.00000        
         0           113.82500           210.80000             0.00000
         0           141.82500           210.80000           180.00000
         0           113.82500           210.80000           180.00000
.END_PLACE_KEEPOUT
.PLACE_KEEPOUT      UNOWNED
TOP 0.00000        
         0            39.00000           164.20000             0.00000
         0            46.50000           164.20000           180.00000
         0            39.00000           164.20000           180.00000
.END_PLACE_KEEPOUT
.PLACE_KEEPOUT      UNOWNED
TOP 0.00000        
         0           163.95000           164.20000             0.00000
         0           171.45000           164.20000           180.00000
         0           163.95000           164.20000           180.00000
.END_PLACE_KEEPOUT
.PLACE_KEEPOUT      UNOWNED
TOP 0.00000        
         0           343.25000           164.20000             0.00000
         0           350.75000           164.20000           180.00000
         0           343.25000           164.20000           180.00000
.END_PLACE_KEEPOUT
.PLACE_KEEPOUT      UNOWNED
TOP 0.00000        
         0           403.35000           164.20000             0.00000
         0           410.85000           164.20000           180.00000
         0           403.35000           164.20000           180.00000
.END_PLACE_KEEPOUT
.PLACE_KEEPOUT      UNOWNED
TOP 0.00000        
         0           479.70000           204.20000             0.00000
         0           487.20000           204.20000           180.00000
         0           479.70000           204.20000           180.00000
.END_PLACE_KEEPOUT
.PLACE_KEEPOUT      UNOWNED
TOP 0.00000        
         0             4.25000           224.20000             0.00000
         0            11.75000           224.20000           180.00000
         0             4.25000           224.20000           180.00000
.END_PLACE_KEEPOUT
.PLACE_KEEPOUT      UNOWNED
TOP 0.20000        
         0           189.80000            79.80000             0.00000
         0           214.80000            79.80000             0.00000
         0           214.80000            53.80000             0.00000
         0           189.80000            53.80000             0.00000
         0           189.80000            79.80000             0.00000
.END_PLACE_KEEPOUT
.PLACE_KEEPOUT      UNOWNED
TOP 0.20000        
         0           287.70000           154.20000             0.00000
         0           312.70000           154.20000             0.00000
         0           312.70000           128.20000             0.00000
         0           287.70000           128.20000             0.00000
         0           287.70000           154.20000             0.00000
.END_PLACE_KEEPOUT
.PLACE_KEEPOUT      UNOWNED
TOP 0.20000        
         0           189.80000           199.80000             0.00000
         0           214.80000           199.80000             0.00000
         0           214.80000           173.80000             0.00000
         0           189.80000           173.80000             0.00000
         0           189.80000           199.80000             0.00000
.END_PLACE_KEEPOUT
.PLACE_KEEPOUT      UNOWNED
TOP 0.20000        
         0           312.70000           233.20000             0.00000
         0           287.70000           233.20000             0.00000
         0           287.70000           259.20000             0.00000
         0           312.70000           259.20000             0.00000
         0           312.70000           233.20000             0.00000
.END_PLACE_KEEPOUT
.PLACE_KEEPOUT      UNOWNED
TOP 0.20000        
         0           256.70000           263.20000             0.00000
         0           231.70000           263.20000             0.00000
         0           231.70000           289.20000             0.00000
         0           256.70000           289.20000             0.00000
         0           256.70000           263.20000             0.00000
.END_PLACE_KEEPOUT
.PLACE_KEEPOUT      UNOWNED
TOP 0.20000        
         0           310.00000           383.20000             0.00000
         0           290.20000           383.20000             0.00000
         0           290.20000           409.20000             0.00000
         0           310.00000           409.20000             0.00000
         0           310.00000           383.20000             0.00000
.END_PLACE_KEEPOUT
.PLACE_KEEPOUT      UNOWNED
TOP 0.20000        
         0           256.70000           350.20000             0.00000
         0           231.70000           350.20000             0.00000
         0           231.70000           376.20000             0.00000
         0           256.70000           376.20000             0.00000
         0           256.70000           350.20000             0.00000
.END_PLACE_KEEPOUT
.PLACE_KEEPOUT      UNOWNED
TOP 0.20000        
         0           195.30000            63.80000             0.00000
         0           195.30000            69.80000             0.00000
         0           209.30000            69.80000          -180.00000
         0           209.30000            63.80000             0.00000
         0           195.30000            63.80000          -180.00000
.END_PLACE_KEEPOUT
.PLACE_KEEPOUT      UNOWNED
TOP 0.20000        
         0           195.30000           183.80000             0.00000
         0           195.30000           189.80000             0.00000
         0           209.30000           189.80000          -180.00000
         0           209.30000           183.80000             0.00000
         0           195.30000           183.80000          -180.00000
.END_PLACE_KEEPOUT
.PLACE_KEEPOUT      UNOWNED
TOP 0.20000        
         0           293.20000           243.20000             0.00000
         0           293.20000           249.20000             0.00000
         0           307.20000           249.20000          -180.00000
         0           307.20000           243.20000             0.00000
         0           293.20000           243.20000          -180.00000
.END_PLACE_KEEPOUT
.PLACE_KEEPOUT      UNOWNED
TOP 0.20000        
         0           237.20000           273.20000             0.00000
         0           237.20000           279.20000             0.00000
         0           251.20000           279.20000          -180.00000
         0           251.20000           273.20000             0.00000
         0           237.20000           273.20000          -180.00000
.END_PLACE_KEEPOUT
.PLACE_KEEPOUT      UNOWNED
TOP 0.20000        
         0           237.20000           360.20000             0.00000
         0           251.20000           360.20000           180.00000
         0           251.20000           366.20000             0.00000
         0           237.20000           366.20000           180.00000
         0           237.20000           360.20000             0.00000
.END_PLACE_KEEPOUT
.PLACE_KEEPOUT      UNOWNED
TOP 0.20000        
         0           293.20000           393.20000             0.00000
         0           307.20000           393.20000           180.00000
         0           307.20000           399.20000             0.00000
         0           293.20000           399.20000           180.00000
         0           293.20000           393.20000             0.00000
.END_PLACE_KEEPOUT
.PLACE_KEEPOUT      UNOWNED
TOP 0.20000        
         0           293.20000           138.20000             0.00000
         0           307.20000           138.20000           180.00000
         0           307.20000           144.20000             0.00000
         0           293.20000           144.20000           180.00000
         0           293.20000           138.20000             0.00000
.END_PLACE_KEEPOUT
.PLACE_KEEPOUT      UNOWNED
TOP 0.00000        
         0           233.50000           -11.80000             0.00000
         0           233.50000           -17.80000             0.00000
         0           246.50000           -17.80000           180.00000
         0           246.50000           -11.80000             0.00000
         0           246.20717            -9.87099            17.26371
         0           244.10929            -6.76376           -59.98480
         0           233.50000           -11.80000           129.21247
.END_PLACE_KEEPOUT
.PLACE_KEEPOUT      UNOWNED
TOP 0.20000        
         0           246.20717            -9.87099             0.00000
         0           250.00000            -9.57246            60.96498
         0           250.00000           -24.80000             0.00000
         0           230.00000           -24.80000             0.00000
         0           230.00000           -10.24700             0.00000
         0           233.60000            -6.50000            87.70756
         0           232.45240            -3.80000            46.05448
         0           245.24760            -3.80000             0.00000
         0           244.10000            -6.50000            46.05448
         0           244.10929            -6.76376             4.03322
         0           233.50000           -11.80000           129.21247
         0           233.50000           -17.80000             0.00000
         0           246.50000           -17.80000           180.00000
         0           246.50000           -11.80000             0.00000
         0           246.20717            -9.87099            17.26371
.END_PLACE_KEEPOUT
.PLACE_KEEPOUT      UNOWNED
TOP 0.00000        
         0           312.67500            20.20000             0.00000
         0           334.67500            20.20000             0.00000
         0           334.67500             0.00000             0.00000
         0           312.67500             0.00000             0.00000
         0           312.67500            20.20000             0.00000
.END_PLACE_KEEPOUT
.PLACE_KEEPOUT      UNOWNED
TOP 0.00000        
         0           452.67500            20.20000             0.00000
         0           474.67500            20.20000             0.00000
         0           474.67500             0.00000             0.00000
         0           452.67500             0.00000             0.00000
         0           452.67500            20.20000             0.00000
.END_PLACE_KEEPOUT
.PLACE_KEEPOUT      UNOWNED
TOP 0.00000        
         0            15.32500            20.20000             0.00000
         0            15.32500             0.00000             0.00000
         0            37.32500             0.00000             0.00000
         0            37.32500            20.20000             0.00000
         0            15.32500            20.20000             0.00000
.END_PLACE_KEEPOUT
.PLACE_KEEPOUT      UNOWNED
TOP 0.00000        
         0           155.32500            20.20000             0.00000
         0           177.32500            20.20000             0.00000
         0           177.32500             0.00000             0.00000
         0           155.32500             0.00000             0.00000
         0           155.32500            20.20000             0.00000
.END_PLACE_KEEPOUT
.PLACE_KEEPOUT      UNOWNED
TOP 0.20000        
         0           191.80000           199.80000             0.00000
         0           198.40000           199.80000             0.00000
         0           198.40000           373.00000             0.00000
         0           191.80000           373.00000             0.00000
         0           191.80000           199.80000             0.00000
.END_PLACE_KEEPOUT
.PLACE_KEEPOUT      UNOWNED
TOP 0.20000        
         0           298.20000           383.20000             0.00000
         0           291.60000           383.20000             0.00000
         0           291.60000           259.20000             0.00000
         0           298.20000           259.20000             0.00000
         0           298.20000           349.20000             0.00000
         0           296.70000           349.20000             0.00000
         0           295.70000           350.20000           -90.00000
         0           295.70000           373.00000             0.00000
         0           296.70000           374.00000           -90.00000
         0           298.20000           374.00000             0.00000
         0           298.20000           383.20000             0.00000
.END_PLACE_KEEPOUT
.PLACE_KEEPOUT      UNOWNED
TOP 0.20000        
         0           298.20000           421.20000             0.00000
         0           291.60000           421.20000             0.00000
         0           291.60000           409.20000             0.00000
         0           298.20000           409.20000             0.00000
         0           298.20000           421.20000             0.00000
.END_PLACE_KEEPOUT
.PLACE_KEEPOUT      UNOWNED
TOP 0.20000        
         0           191.80000            79.80000             0.00000
         0           198.40000            79.80000             0.00000
         0           198.40000           173.80000             0.00000
         0           191.80000           173.80000             0.00000
         0           191.80000            79.80000             0.00000
.END_PLACE_KEEPOUT
.PLACE_KEEPOUT      UNOWNED
TOP 0.20000        
         0           298.20000           233.20000             0.00000
         0           291.60000           233.20000             0.00000
         0           291.60000           154.20000             0.00000
         0           298.20000           154.20000             0.00000
         0           298.20000           233.20000             0.00000
.END_PLACE_KEEPOUT
.PLACE_KEEPOUT      UNOWNED
TOP 0.20000        
         0           198.40000            53.80000             0.00000
         0           191.80000            53.80000             0.00000
         0           191.80000             0.00000             0.00000
         0           198.40000             0.00000             0.00000
         0           198.40000            53.80000             0.00000
.END_PLACE_KEEPOUT
.PLACE_KEEPOUT      UNOWNED
TOP 0.20000        
         0           298.20000           128.20000             0.00000
         0           291.60000           128.20000             0.00000
         0           291.60000           -38.80000             0.00000
         0           298.20000           -38.80000             0.00000
         0           298.20000           128.20000             0.00000
.END_PLACE_KEEPOUT
.PLACE_KEEPOUT      UNOWNED
TOP 0.20000        
         0           334.67500            10.00000             0.00000
         0           334.67500             0.00000             0.00000
         0           347.00000            -0.00000             0.00000
         0           348.00000             1.00000            90.00000
         0           348.00000            10.00000             0.00000
         0           334.67500            10.00000             0.00000
.END_PLACE_KEEPOUT
.PLACE_KEEPOUT      UNOWNED
TOP 0.20000        
         0           396.00000            10.00000             0.00000
         0           396.00000             1.00000             0.00000
         0           397.00000             0.00000            90.00000
         0           452.67500            -0.00000             0.00000
         0           452.67500            10.00000             0.00000
         0           396.00000            10.00000             0.00000
.END_PLACE_KEEPOUT
.PLACE_KEEPOUT      UNOWNED
TOP 0.20000        
         0           474.67500            10.00000             0.00000
         0           474.67500            -0.00000             0.00000
         0           490.45000            -0.00000             0.00000
         0           491.45000             1.00000            90.00000
         0           491.45000            10.00000             0.00000
         0           474.67500            10.00000             0.00000
.END_PLACE_KEEPOUT
.PLACE_KEEPOUT      UNOWNED
TOP 0.20000        
         0           150.00000            10.00000             0.00000
         0           155.32500            10.00000             0.00000
         0           155.32500             0.00000             0.00000
         0           151.00000             0.00000             0.00000
         0           150.00000             1.00000           -90.00000
         0           150.00000            10.00000             0.00000
.END_PLACE_KEEPOUT
.PLACE_KEEPOUT      UNOWNED
TOP 0.20000        
         0           102.00000             1.00000             0.00000
         0           102.00000            10.00000             0.00000
         0            37.32500            10.00000             0.00000
         0            37.32500            -0.00000             0.00000
         0           101.00000            -0.00000             0.00000
         0           102.00000             1.00000            90.00000
.END_PLACE_KEEPOUT
.PLACE_KEEPOUT      UNOWNED
TOP 0.20000        
         0             0.00000            10.00000             0.00000
         0            15.32500            10.00000             0.00000
         0            15.32500            -0.00000             0.00000
         0             1.00000            -0.00000             0.00000
         0             0.00000             1.00000           -90.00000
         0             0.00000            10.00000             0.00000
.END_PLACE_KEEPOUT
.PLACE_KEEPOUT      UNOWNED
TOP 0.20000        
         0           485.00000             5.50000             0.00000
         0           477.50000             5.50000           180.00000
         0           485.00000             5.50000           180.00000
.END_PLACE_KEEPOUT
.PLACE_KEEPOUT      UNOWNED
TOP 0.20000        
         0             7.60000             5.50000             0.00000
         0             0.10000             5.50000           180.00000
         0             7.60000             5.50000           180.00000
.END_PLACE_KEEPOUT
.PLACE_KEEPOUT      UNOWNED
TOP 0.20000        
         0            86.00000           295.80000             0.00000
         0            71.45000           295.80000             0.00000
         0            71.45000           305.80000             0.00000
         0            54.45000           305.80000             0.00000
         0            54.45000           295.80000             0.00000
         0            39.90000           295.80000             0.00000
         0            39.90000           305.80000             0.00000
         0            22.90000           305.80000             0.00000
         0            22.90000           295.80000             0.00000
         0             8.35000           295.80000             0.00000
         0             8.35000           305.80000             0.00000
         0             0.00000           305.80000             0.00000
         0             0.00000           348.20000             0.00000
         0             1.00000           349.20000           -90.00000
         0           189.70000           349.20000             0.00000
         0           190.70000           350.20000            90.00000
         0           190.70000           372.00000             0.00000
         0           191.70000           373.00000           -90.00000
         0           191.80000           373.00000             0.00000
         0           191.80000           305.80000             0.00000
         0           180.65000           305.80000             0.00000
         0           180.65000           295.80000             0.00000
         0           166.10000           295.80000             0.00000
         0           166.10000           305.80000             0.00000
         0           149.10000           305.80000             0.00000
         0           149.10000           295.80000             0.00000
         0           134.55000           295.80000             0.00000
         0           134.55000           305.80000             0.00000
         0           117.55000           305.80000             0.00000
         0           117.55000           295.80000             0.00000
         0           103.00000           295.80000             0.00000
         0           103.00000           305.80000             0.00000
         0            86.00000           305.80000             0.00000
         0            86.00000           295.80000             0.00000
.END_PLACE_KEEPOUT
.PLACE_KEEPOUT      UNOWNED
TOP 0.20000        
         0           152.32500           322.80000             0.00000
         0           166.32500           322.80000           180.00000
         0           166.32500           328.80000             0.00000
         0           152.32500           328.80000           180.00000
         0           152.32500           322.80000             0.00000
.END_PLACE_KEEPOUT
.PLACE_KEEPOUT      UNOWNED
TOP 0.20000        
         0            89.32500           322.80000             0.00000
         0           103.32500           322.80000           180.00000
         0           103.32500           328.80000             0.00000
         0            89.32500           328.80000           180.00000
         0            89.32500           322.80000             0.00000
.END_PLACE_KEEPOUT
.PLACE_KEEPOUT      UNOWNED
TOP 0.20000        
         0            26.32500           322.80000             0.00000
         0            40.32500           322.80000           180.00000
         0            40.32500           328.80000             0.00000
         0            26.32500           328.80000           180.00000
         0            26.32500           322.80000             0.00000
.END_PLACE_KEEPOUT
.PLACE_KEEPOUT      UNOWNED
TOP 0.20000        
         0           320.25000           295.80000             0.00000
         0           305.70000           295.80000             0.00000
         0           305.70000           305.80000             0.00000
         0           298.20000           305.80000             0.00000
         0           298.20000           349.20000             0.00000
         0           490.45000           349.20000             0.00000
         0           491.45000           348.20000           -90.00000
         0           491.45000           305.80000             0.00000
         0           478.00000           305.80000             0.00000
         0           478.00000           295.80000             0.00000
         0           463.45000           295.80000             0.00000
         0           463.45000           305.80000             0.00000
         0           446.45000           305.80000             0.00000
         0           446.45000           295.80000             0.00000
         0           431.90000           295.80000             0.00000
         0           431.90000           305.80000             0.00000
         0           414.90000           305.80000             0.00000
         0           414.90000           295.80000             0.00000
         0           400.35000           295.80000             0.00000
         0           400.35000           305.80000             0.00000
         0           383.35000           305.80000             0.00000
         0           383.35000           295.80000             0.00000
         0           368.80000           295.80000             0.00000
         0           368.80000           305.80000             0.00000
         0           351.80000           305.80000             0.00000
         0           351.80000           295.80000             0.00000
         0           337.25000           295.80000             0.00000
         0           337.25000           305.80000             0.00000
         0           320.25000           305.80000             0.00000
         0           320.25000           295.80000             0.00000
.END_PLACE_KEEPOUT
.PLACE_KEEPOUT      UNOWNED
TOP 0.20000        
         0           323.67500           322.80000             0.00000
         0           337.67500           322.80000           180.00000
         0           337.67500           328.80000             0.00000
         0           323.67500           328.80000           180.00000
         0           323.67500           322.80000             0.00000
.END_PLACE_KEEPOUT
.PLACE_KEEPOUT      UNOWNED
TOP 0.20000        
         0           386.67500           322.80000             0.00000
         0           400.67500           322.80000           180.00000
         0           400.67500           328.80000             0.00000
         0           386.67500           328.80000           180.00000
         0           386.67500           322.80000             0.00000
.END_PLACE_KEEPOUT
.PLACE_KEEPOUT      UNOWNED
TOP 0.20000        
         0           449.67500           322.80000             0.00000
         0           463.67500           322.80000           180.00000
         0           463.67500           328.80000             0.00000
         0           449.67500           328.80000           180.00000
         0           449.67500           322.80000             0.00000
.END_PLACE_KEEPOUT
.PLACE_KEEPOUT      UNOWNED
TOP 0.20000        
         0           298.20000           409.20000             0.00000
         0           310.00000           409.20000             0.00000
         0           310.00000           420.20000             0.00000
         0           309.00000           421.20000            90.00000
         0           298.20000           421.20000             0.00000
         0           298.20000           409.20000             0.00000
.END_PLACE_KEEPOUT
.PLACE_KEEPOUT      UNOWNED
TOP 0.20000        
         0           298.20000           374.00000             0.00000
         0           309.00000           374.00000             0.00000
         0           310.00000           375.00000            90.00000
         0           310.00000           383.20000             0.00000
         0           298.20000           383.20000             0.00000
         0           298.20000           374.00000             0.00000
.END_PLACE_KEEPOUT
.PLACE_KEEPOUT      UNOWNED
TOP 0.20000        
         0           312.70000           240.80000             0.00000
         0           491.45000           240.80000             0.00000
         0           491.45000           190.80000             0.00000
         0           478.00000           190.80000             0.00000
         0           478.00000           180.80000             0.00000
         0           463.45000           180.80000             0.00000
         0           463.45000           190.80000             0.00000
         0           446.45000           190.80000             0.00000
         0           446.45000           180.80000             0.00000
         0           431.90000           180.80000             0.00000
         0           431.90000           190.80000             0.00000
         0           414.90000           190.80000             0.00000
         0           414.90000           180.80000             0.00000
         0           400.35000           180.80000             0.00000
         0           400.35000           190.80000             0.00000
         0           383.35000           190.80000             0.00000
         0           383.35000           180.80000             0.00000
         0           368.80000           180.80000             0.00000
         0           368.80000           190.80000             0.00000
         0           351.80000           190.80000             0.00000
         0           351.80000           180.80000             0.00000
         0           337.25000           180.80000             0.00000
         0           337.25000           190.80000             0.00000
         0           320.25000           190.80000             0.00000
         0           320.25000           180.80000             0.00000
         0           305.70000           180.80000             0.00000
         0           305.70000           190.80000             0.00000
         0           298.20000           190.80000             0.00000
         0           298.20000           233.20000             0.00000
         0           312.70000           233.20000             0.00000
         0           312.70000           240.80000             0.00000
.END_PLACE_KEEPOUT
.PLACE_KEEPOUT      UNOWNED
TOP 0.20000        
         0           323.67500           207.80000             0.00000
         0           337.67500           207.80000           180.00000
         0           337.67500           213.80000             0.00000
         0           323.67500           213.80000           180.00000
         0           323.67500           207.80000             0.00000
.END_PLACE_KEEPOUT
.PLACE_KEEPOUT      UNOWNED
TOP 0.20000        
         0           386.67500           207.80000             0.00000
         0           400.67500           207.80000           180.00000
         0           400.67500           213.80000             0.00000
         0           386.67500           213.80000           180.00000
         0           386.67500           207.80000             0.00000
.END_PLACE_KEEPOUT
.PLACE_KEEPOUT      UNOWNED
TOP 0.20000        
         0           439.17500           210.80000             0.00000
         0           411.17500           210.80000           180.00000
         0           439.17500           210.80000           180.00000
.END_PLACE_KEEPOUT
.PLACE_KEEPOUT      UNOWNED
TOP 0.20000        
         0           449.67500           207.80000             0.00000
         0           463.67500           207.80000           180.00000
         0           463.67500           213.80000             0.00000
         0           449.67500           213.80000           180.00000
         0           449.67500           207.80000             0.00000
.END_PLACE_KEEPOUT
.PLACE_KEEPOUT      UNOWNED
TOP 0.20000        
         0           191.80000           199.80000             0.00000
         0           191.80000           240.80000             0.00000
         0             0.00000           240.80000             0.00000
         0             0.00000           190.80000             0.00000
         0             8.35000           190.80000             0.00000
         0             8.35000           180.80000             0.00000
         0            22.90000           180.80000             0.00000
         0            22.90000           190.80000             0.00000
         0            39.90000           190.80000             0.00000
         0            39.90000           180.80000             0.00000
         0            54.45000           180.80000             0.00000
         0            54.45000           190.80000             0.00000
         0            71.45000           190.80000             0.00000
         0            71.45000           180.80000             0.00000
         0            86.00000           180.80000             0.00000
         0            86.00000           190.80000             0.00000
         0           103.00000           190.80000             0.00000
         0           103.00000           180.80000             0.00000
         0           117.55000           180.80000             0.00000
         0           117.55000           190.80000             0.00000
         0           134.55000           190.80000             0.00000
         0           134.55000           180.80000             0.00000
         0           149.10000           180.80000             0.00000
         0           149.10000           190.80000             0.00000
         0           166.10000           190.80000             0.00000
         0           166.10000           180.80000             0.00000
         0           180.65000           180.80000             0.00000
         0           180.65000           190.80000             0.00000
         0           189.80000           190.80000             0.00000
         0           189.80000           199.80000             0.00000
         0           191.80000           199.80000             0.00000
.END_PLACE_KEEPOUT
.PLACE_KEEPOUT      UNOWNED
TOP 0.20000        
         0           152.32500           207.80000             0.00000
         0           152.32500           213.80000             0.00000
         0           166.32500           213.80000          -180.00000
         0           166.32500           207.80000             0.00000
         0           152.32500           207.80000          -180.00000
.END_PLACE_KEEPOUT
.PLACE_KEEPOUT      UNOWNED
TOP 0.20000        
         0           113.82500           210.80000             0.00000
         0           141.82500           210.80000           180.00000
         0           113.82500           210.80000           180.00000
.END_PLACE_KEEPOUT
.PLACE_KEEPOUT      UNOWNED
TOP 0.20000        
         0            89.32500           207.80000             0.00000
         0            89.32500           213.80000             0.00000
         0           103.32500           213.80000          -180.00000
         0           103.32500           207.80000             0.00000
         0            89.32500           207.80000          -180.00000
.END_PLACE_KEEPOUT
.PLACE_KEEPOUT      UNOWNED
TOP 0.20000        
         0            26.32500           207.80000             0.00000
         0            26.32500           213.80000             0.00000
         0            40.32500           213.80000          -180.00000
         0            40.32500           207.80000             0.00000
         0            26.32500           207.80000          -180.00000
.END_PLACE_KEEPOUT
.PLACE_KEEPOUT      UNOWNED
TOP 0.20000        
         0           312.70000           125.80000             0.00000
         0           491.45000           125.80000             0.00000
         0           491.45000            75.80000             0.00000
         0           478.00000            75.80000             0.00000
         0           478.00000            65.80000             0.00000
         0           463.45000            65.80000             0.00000
         0           463.45000            75.80000             0.00000
         0           446.45000            75.80000             0.00000
         0           446.45000            65.80000             0.00000
         0           431.90000            65.80000             0.00000
         0           431.90000            75.80000             0.00000
         0           414.90000            75.80000             0.00000
         0           414.90000            65.80000             0.00000
         0           400.35000            65.80000             0.00000
         0           400.35000            75.80000             0.00000
         0           383.35000            75.80000             0.00000
         0           383.35000            65.80000             0.00000
         0           368.80000            65.80000             0.00000
         0           368.80000            75.80000             0.00000
         0           351.80000            75.80000             0.00000
         0           351.80000            65.80000             0.00000
         0           337.25000            65.80000             0.00000
         0           337.25000            75.80000             0.00000
         0           320.25000            75.80000             0.00000
         0           320.25000            65.80000             0.00000
         0           305.70000            65.80000             0.00000
         0           305.70000            75.80000             0.00000
         0           298.20000            75.80000             0.00000
         0           298.20000           128.20000             0.00000
         0           312.70000           128.20000             0.00000
         0           312.70000           125.80000             0.00000
.END_PLACE_KEEPOUT
.PLACE_KEEPOUT      UNOWNED
TOP 0.20000        
         0           323.67500            92.80000             0.00000
         0           337.67500            92.80000           180.00000
         0           337.67500            98.80000             0.00000
         0           323.67500            98.80000           180.00000
         0           323.67500            92.80000             0.00000
.END_PLACE_KEEPOUT
.PLACE_KEEPOUT      UNOWNED
TOP 0.20000        
         0           386.67500            92.80000             0.00000
         0           400.67500            92.80000           180.00000
         0           400.67500            98.80000             0.00000
         0           386.67500            98.80000           180.00000
         0           386.67500            92.80000             0.00000
.END_PLACE_KEEPOUT
.PLACE_KEEPOUT      UNOWNED
TOP 0.20000        
         0           485.00000           120.50000             0.00000
         0           477.50000           120.50000           180.00000
         0           485.00000           120.50000           180.00000
.END_PLACE_KEEPOUT
.PLACE_KEEPOUT      UNOWNED
TOP 0.20000        
         0           449.67500            92.80000             0.00000
         0           463.67500            92.80000           180.00000
         0           463.67500            98.80000             0.00000
         0           449.67500            98.80000           180.00000
         0           449.67500            92.80000             0.00000
.END_PLACE_KEEPOUT
.PLACE_KEEPOUT      UNOWNED
TOP 0.20000        
         0           312.67500             0.00000             0.00000
         0           312.67500            10.00000             0.00000
         0           298.20000            10.00000             0.00000
         0           298.20000           -38.80000             0.00000
         0           299.00000           -38.80000             0.00000
         0           300.00000           -37.80000            90.00000
         0           300.00000            -1.00000             0.00000
         0           301.00000             0.00000           -90.00000
         0           312.67500             0.00000             0.00000
.END_PLACE_KEEPOUT
.PLACE_KEEPOUT      UNOWNED
TOP 0.20000        
         0           177.32500            10.00000             0.00000
         0           177.32500             0.00000             0.00000
         0           191.80000             0.00000             0.00000
         0           191.80000            10.00000             0.00000
         0           177.32500            10.00000             0.00000
.END_PLACE_KEEPOUT
.PLACE_KEEPOUT      UNOWNED
TOP 0.20000        
         0           191.80000            79.80000             0.00000
         0           191.80000           125.80000             0.00000
         0             0.00000           125.80000             0.00000
         0             0.00000            75.80000             0.00000
         0             8.35000            75.80000             0.00000
         0             8.35000            65.80000             0.00000
         0            22.90000            65.80000             0.00000
         0            22.90000            75.80000             0.00000
         0            39.90000            75.80000             0.00000
         0            39.90000            65.80000             0.00000
         0            54.45000            65.80000             0.00000
         0            54.45000            75.80000             0.00000
         0            71.45000            75.80000             0.00000
         0            71.45000            65.80000             0.00000
         0            86.00000            65.80000             0.00000
         0            86.00000            75.80000             0.00000
         0           103.00000            75.80000             0.00000
         0           103.00000            65.80000             0.00000
         0           117.55000            65.80000             0.00000
         0           117.55000            75.80000             0.00000
         0           134.55000            75.80000             0.00000
         0           134.55000            65.80000             0.00000
         0           149.10000            65.80000             0.00000
         0           149.10000            75.80000             0.00000
         0           166.10000            75.80000             0.00000
         0           166.10000            65.80000             0.00000
         0           180.65000            65.80000             0.00000
         0           180.65000            79.80000             0.00000
         0           191.80000            79.80000             0.00000
.END_PLACE_KEEPOUT
.PLACE_KEEPOUT      UNOWNED
TOP 0.20000        
         0           152.32500            92.80000             0.00000
         0           152.32500            98.80000             0.00000
         0           166.32500            98.80000          -180.00000
         0           166.32500            92.80000             0.00000
         0           152.32500            92.80000          -180.00000
.END_PLACE_KEEPOUT
.PLACE_KEEPOUT      UNOWNED
TOP 0.20000        
         0             7.60000           120.50000             0.00000
         0             0.10000           120.50000           180.00000
         0             7.60000           120.50000           180.00000
.END_PLACE_KEEPOUT
.PLACE_KEEPOUT      UNOWNED
TOP 0.20000        
         0            26.32500            92.80000             0.00000
         0            26.32500            98.80000             0.00000
         0            40.32500            98.80000          -180.00000
         0            40.32500            92.80000             0.00000
         0            26.32500            92.80000          -180.00000
.END_PLACE_KEEPOUT
.PLACE_KEEPOUT      UNOWNED
TOP 0.20000        
         0            89.32500            92.80000             0.00000
         0            89.32500            98.80000             0.00000
         0           103.32500            98.80000          -180.00000
         0           103.32500            92.80000             0.00000
         0            89.32500            92.80000          -180.00000
.END_PLACE_KEEPOUT
.PLACE_KEEPOUT      UNOWNED
TOP 0.20000        
         0           186.15000           208.50000             0.00000
         0           178.65000           208.50000           180.00000
         0           186.15000           208.50000           180.00000
.END_PLACE_KEEPOUT
.PLACE_KEEPOUT      UNOWNED
TOP 0.20000        
         0            11.75000           224.20000             0.00000
         0             4.25000           224.20000           180.00000
         0            11.75000           224.20000           180.00000
.END_PLACE_KEEPOUT
.PLACE_KEEPOUT      UNOWNED
TOP 0.20000        
         0           375.35000           220.20000             0.00000
         0           367.85000           220.20000           180.00000
         0           375.35000           220.20000           180.00000
.END_PLACE_KEEPOUT
.PLACE_KEEPOUT      UNOWNED
TOP 0.20000        
         0           487.20000           204.20000             0.00000
         0           479.70000           204.20000           180.00000
         0           487.20000           204.20000           180.00000
.END_PLACE_KEEPOUT
.PLACE_KEEPOUT      UNOWNED
TOP 2.00000        
         0           312.70000           240.80000             0.00000
         0           491.45000           240.80000             0.00000
         0           491.45000           305.80000             0.00000
         0           478.00000           305.80000             0.00000
         0           478.00000           295.80000             0.00000
         0           463.45000           295.80000             0.00000
         0           463.45000           305.80000             0.00000
         0           446.45000           305.80000             0.00000
         0           446.45000           295.80000             0.00000
         0           431.90000           295.80000             0.00000
         0           431.90000           305.80000             0.00000
         0           414.90000           305.80000             0.00000
         0           414.90000           295.80000             0.00000
         0           400.35000           295.80000             0.00000
         0           400.35000           305.80000             0.00000
         0           383.35000           305.80000             0.00000
         0           383.35000           295.80000             0.00000
         0           368.80000           295.80000             0.00000
         0           368.80000           305.80000             0.00000
         0           351.80000           305.80000             0.00000
         0           351.80000           295.80000             0.00000
         0           337.25000           295.80000             0.00000
         0           337.25000           305.80000             0.00000
         0           320.25000           305.80000             0.00000
         0           320.25000           295.80000             0.00000
         0           305.70000           295.80000             0.00000
         0           305.70000           305.80000             0.00000
         0           298.20000           305.80000             0.00000
         0           298.20000           259.20000             0.00000
         0           312.70000           259.20000             0.00000
         0           312.70000           240.80000             0.00000
.END_PLACE_KEEPOUT
.PLACE_KEEPOUT      UNOWNED
TOP 2.00000        
         0           312.70000           125.80000             0.00000
         0           491.45000           125.80000             0.00000
         0           491.45000           190.80000             0.00000
         0           478.00000           190.80000             0.00000
         0           478.00000           180.80000             0.00000
         0           463.45000           180.80000             0.00000
         0           463.45000           190.80000             0.00000
         0           446.45000           190.80000             0.00000
         0           446.45000           180.80000             0.00000
         0           431.90000           180.80000             0.00000
         0           431.90000           190.80000             0.00000
         0           414.90000           190.80000             0.00000
         0           414.90000           180.80000             0.00000
         0           400.35000           180.80000             0.00000
         0           400.35000           190.80000             0.00000
         0           383.35000           190.80000             0.00000
         0           383.35000           180.80000             0.00000
         0           368.80000           180.80000             0.00000
         0           368.80000           190.80000             0.00000
         0           351.80000           190.80000             0.00000
         0           351.80000           180.80000             0.00000
         0           337.25000           180.80000             0.00000
         0           337.25000           190.80000             0.00000
         0           320.25000           190.80000             0.00000
         0           320.25000           180.80000             0.00000
         0           305.70000           180.80000             0.00000
         0           305.70000           190.80000             0.00000
         0           298.20000           190.80000             0.00000
         0           298.20000           154.20000             0.00000
         0           312.70000           154.20000             0.00000
         0           312.70000           125.80000             0.00000
.END_PLACE_KEEPOUT
.PLACE_KEEPOUT      UNOWNED
TOP 2.00000        
         0           491.45000            75.80000             0.00000
         0           491.45000            10.00000             0.00000
         0           474.67500            10.00000             0.00000
         0           474.67500            20.20000             0.00000
         0           452.67500            20.20000             0.00000
         0           452.67500            10.00000             0.00000
         0           396.00000            10.00000             0.00000
         0           396.00000            14.00000             0.00000
         0           395.00000            15.00000            90.00000
         0           349.00000            15.00000             0.00000
         0           348.00000            14.00000            90.00000
         0           348.00000            10.00000             0.00000
         0           334.67500            10.00000             0.00000
         0           334.67500            20.20000             0.00000
         0           312.67500            20.20000             0.00000
         0           312.67500            10.00000             0.00000
         0           298.20000            10.00000             0.00000
         0           298.20000            75.80000             0.00000
         0           305.70000            75.80000             0.00000
         0           305.70000            65.80000             0.00000
         0           320.25000            65.80000             0.00000
         0           320.25000            75.80000             0.00000
         0           337.25000            75.80000             0.00000
         0           337.25000            65.80000             0.00000
         0           351.80000            65.80000             0.00000
         0           351.80000            75.80000             0.00000
         0           368.80000            75.80000             0.00000
         0           368.80000            65.80000             0.00000
         0           383.35000            65.80000             0.00000
         0           383.35000            75.80000             0.00000
         0           400.35000            75.80000             0.00000
         0           400.35000            65.80000             0.00000
         0           414.90000            65.80000             0.00000
         0           414.90000            75.80000             0.00000
         0           431.90000            75.80000             0.00000
         0           431.90000            65.80000             0.00000
         0           446.45000            65.80000             0.00000
         0           446.45000            75.80000             0.00000
         0           463.45000            75.80000             0.00000
         0           463.45000            65.80000             0.00000
         0           478.00000            65.80000             0.00000
         0           478.00000            75.80000             0.00000
         0           491.45000            75.80000             0.00000
.END_PLACE_KEEPOUT
.PLACE_KEEPOUT      UNOWNED
TOP 2.00000        
         0             0.00000            10.00000             0.00000
         0            15.32500            10.00000             0.00000
         0            15.32500            20.20000             0.00000
         0            37.32500            20.20000             0.00000
         0            37.32500            10.00000             0.00000
         0           102.00000            10.00000             0.00000
         0           102.00000            14.00000             0.00000
         0           103.00000            15.00000           -90.00000
         0           149.00000            15.00000             0.00000
         0           150.00000            14.00000           -90.00000
         0           150.00000            10.00000             0.00000
         0           155.32500            10.00000             0.00000
         0           155.32500            20.20000             0.00000
         0           177.32500            20.20000             0.00000
         0           177.32500            10.00000             0.00000
         0           191.80000            10.00000             0.00000
         0           191.80000            53.80000             0.00000
         0           189.80000            53.80000             0.00000
         0           189.80000            79.80000             0.00000
         0           180.65000            79.80000             0.00000
         0           180.65000            65.80000             0.00000
         0           166.10000            65.80000             0.00000
         0           166.10000            75.80000             0.00000
         0           149.10000            75.80000             0.00000
         0           149.10000            65.80000             0.00000
         0           134.55000            65.80000             0.00000
         0           134.55000            75.80000             0.00000
         0           117.55000            75.80000             0.00000
         0           117.55000            65.80000             0.00000
         0           103.00000            65.80000             0.00000
         0           103.00000            75.80000             0.00000
         0            86.00000            75.80000             0.00000
         0            86.00000            65.80000             0.00000
         0            71.45000            65.80000             0.00000
         0            71.45000            75.80000             0.00000
         0            54.45000            75.80000             0.00000
         0            54.45000            65.80000             0.00000
         0            39.90000            65.80000             0.00000
         0            39.90000            75.80000             0.00000
         0            22.90000            75.80000             0.00000
         0            22.90000            65.80000             0.00000
         0             8.35000            65.80000             0.00000
         0             8.35000            75.80000             0.00000
         0             0.00000            75.80000             0.00000
         0             0.00000            10.00000             0.00000
.END_PLACE_KEEPOUT
.PLACE_KEEPOUT      UNOWNED
TOP 2.00000        
         0             0.00000           125.80000             0.00000
         0           191.80000           125.80000             0.00000
         0           191.80000           173.80000             0.00000
         0           189.80000           173.80000             0.00000
         0           189.80000           190.80000             0.00000
         0           180.65000           190.80000             0.00000
         0           180.65000           180.80000             0.00000
         0           166.10000           180.80000             0.00000
         0           166.10000           190.80000             0.00000
         0           149.10000           190.80000             0.00000
         0           149.10000           180.80000             0.00000
         0           134.55000           180.80000             0.00000
         0           134.55000           190.80000             0.00000
         0           117.55000           190.80000             0.00000
         0           117.55000           180.80000             0.00000
         0           103.00000           180.80000             0.00000
         0           103.00000           190.80000             0.00000
         0            86.00000           190.80000             0.00000
         0            86.00000           180.80000             0.00000
         0            71.45000           180.80000             0.00000
         0            71.45000           190.80000             0.00000
         0            54.45000           190.80000             0.00000
         0            54.45000           180.80000             0.00000
         0            39.90000           180.80000             0.00000
         0            39.90000           190.80000             0.00000
         0            22.90000           190.80000             0.00000
         0            22.90000           180.80000             0.00000
         0             8.35000           180.80000             0.00000
         0             8.35000           190.80000             0.00000
         0             0.00000           190.80000             0.00000
         0             0.00000           125.80000             0.00000
.END_PLACE_KEEPOUT
.PLACE_KEEPOUT      UNOWNED
TOP 2.00000        
         0             0.00000           240.80000             0.00000
         0           191.80000           240.80000             0.00000
         0           191.80000           305.80000             0.00000
         0           180.65000           305.80000             0.00000
         0           180.65000           295.80000             0.00000
         0           166.10000           295.80000             0.00000
         0           166.10000           305.80000             0.00000
         0           149.10000           305.80000             0.00000
         0           149.10000           295.80000             0.00000
         0           134.55000           295.80000             0.00000
         0           134.55000           305.80000             0.00000
         0           117.55000           305.80000             0.00000
         0           117.55000           295.80000             0.00000
         0           103.00000           295.80000             0.00000
         0           103.00000           305.80000             0.00000
         0            86.00000           305.80000             0.00000
         0            86.00000           295.80000             0.00000
         0            71.45000           295.80000             0.00000
         0            71.45000           305.80000             0.00000
         0            54.45000           305.80000             0.00000
         0            54.45000           295.80000             0.00000
         0            39.90000           295.80000             0.00000
         0            39.90000           305.80000             0.00000
         0            22.90000           305.80000             0.00000
         0            22.90000           295.80000             0.00000
         0             8.35000           295.80000             0.00000
         0             8.35000           305.80000             0.00000
         0             0.00000           305.80000             0.00000
         0             0.00000           240.80000             0.00000
.END_PLACE_KEEPOUT
.PLACE_KEEPOUT      UNOWNED
TOP 2.00000        
         0            48.75000           270.00000             0.00000
         0            39.25000           270.00000           180.00000
         0            48.75000           270.00000           180.00000
.END_PLACE_KEEPOUT
.PLACE_KEEPOUT      UNOWNED
TOP 2.00000        
         0           111.85000           290.00000             0.00000
         0           102.35000           290.00000           180.00000
         0           111.85000           290.00000           180.00000
.END_PLACE_KEEPOUT
.PLACE_KEEPOUT      UNOWNED
TOP 2.00000        
         0           174.95000           270.00000             0.00000
         0           165.45000           270.00000           180.00000
         0           174.95000           270.00000           180.00000
.END_PLACE_KEEPOUT
.PLACE_KEEPOUT      UNOWNED
TOP 2.00000        
         0           346.05000           270.00000             0.00000
         0           336.55000           270.00000           180.00000
         0           346.05000           270.00000           180.00000
.END_PLACE_KEEPOUT
.PLACE_KEEPOUT      UNOWNED
TOP 2.00000        
         0           409.15000           290.00000             0.00000
         0           399.65000           290.00000           180.00000
         0           409.15000           290.00000           180.00000
.END_PLACE_KEEPOUT
.PLACE_KEEPOUT      UNOWNED
TOP 2.00000        
         0           472.25000           270.00000             0.00000
         0           462.75000           270.00000           180.00000
         0           472.25000           270.00000           180.00000
.END_PLACE_KEEPOUT
.PLACE_KEEPOUT      UNOWNED
TOP 2.00000        
         0           350.75000           164.20000             0.00000
         0           343.25000           164.20000           180.00000
         0           350.75000           164.20000           180.00000
.END_PLACE_KEEPOUT
.PLACE_KEEPOUT      UNOWNED
TOP 2.00000        
         0           410.85000           164.20000             0.00000
         0           403.35000           164.20000           180.00000
         0           410.85000           164.20000           180.00000
.END_PLACE_KEEPOUT
.PLACE_KEEPOUT      UNOWNED
TOP 2.00000        
         0            46.50000           164.20000             0.00000
         0            39.00000           164.20000           180.00000
         0            46.50000           164.20000           180.00000
.END_PLACE_KEEPOUT
.PLACE_KEEPOUT      UNOWNED
TOP 2.00000        
         0           171.45000           164.20000             0.00000
         0           163.95000           164.20000           180.00000
         0           171.45000           164.20000           180.00000
.END_PLACE_KEEPOUT
.PLACE_KEEPOUT      UNOWNED
TOP 2.00000        
         0           129.15000            28.08000             0.00000
         0           123.15000            28.08000           180.00000
         0           129.15000            28.08000           180.00000
.END_PLACE_KEEPOUT
.PLACE_KEEPOUT      UNOWNED
TOP 2.00000        
         0           375.15000            28.08000             0.00000
         0           369.15000            28.08000           180.00000
         0           375.15000            28.08000           180.00000
.END_PLACE_KEEPOUT
.PLACE_KEEPOUT      UNOWNED
TOP 2.00000        
         0           370.94500            20.55000             0.00000
         0           373.35500            20.55000           180.00000
         0           370.94500            20.55000           180.00000
.END_PLACE_KEEPOUT
.PLACE_KEEPOUT      UNOWNED
TOP 2.00000        
         0           124.94500            20.55000             0.00000
         0           127.35500            20.55000           180.00000
         0           124.94500            20.55000           180.00000
.END_PLACE_KEEPOUT
.PLACE_KEEPOUT      UNOWNED
TOP 2.00000        
         0            45.40000           283.00000             0.00000
         0            42.60000           283.00000           180.00000
         0            45.40000           283.00000           180.00000
.END_PLACE_KEEPOUT
.PLACE_KEEPOUT      UNOWNED
TOP 2.00000        
         0           171.60000           283.00000             0.00000
         0           168.80000           283.00000           180.00000
         0           171.60000           283.00000           180.00000
.END_PLACE_KEEPOUT
.PLACE_KEEPOUT      UNOWNED
TOP 2.00000        
         0           342.70000           283.00000             0.00000
         0           339.90000           283.00000           180.00000
         0           342.70000           283.00000           180.00000
.END_PLACE_KEEPOUT
.PLACE_KEEPOUT      UNOWNED
TOP 2.00000        
         0           468.90000           283.00000             0.00000
         0           466.10000           283.00000           180.00000
         0           468.90000           283.00000           180.00000
.END_PLACE_KEEPOUT
.PLACE_KEEPOUT      UNOWNED
TOP 3.50000        
         0           198.40000           199.80000             0.00000
         0           214.80000           199.80000             0.00000
         0           214.80000           173.80000             0.00000
         0           198.40000           173.80000             0.00000
         0           198.40000           167.70000             0.00000
         0           200.35000           167.70000             0.00000
         0           208.05000           167.70000             0.00000
         0           208.05000           158.30000             0.00000
         0           200.35000           158.30000             0.00000
         0           200.35000           167.60000             0.00000
         0           198.40000           167.60000             0.00000
         0           198.40000           130.35000             0.00000
         0           287.70000           130.35000             0.00000
         0           287.70000           154.20000             0.00000
         0           291.60000           154.20000             0.00000
         0           291.60000           229.00000             0.00000
         0           289.65000           229.00000             0.00000
         0           289.65000           219.70000             0.00000
         0           281.95000           219.70000             0.00000
         0           281.95000           229.10000             0.00000
         0           289.65000           229.10000             0.00000
         0           291.60000           229.10000             0.00000
         0           291.60000           233.20000             0.00000
         0           287.70000           233.20000             0.00000
         0           287.70000           239.53000             0.00000
         0           284.70000           239.53000             0.00000
         0           284.70000           230.23000             0.00000
         0           277.00000           230.23000             0.00000
         0           277.00000           239.63000             0.00000
         0           284.70000           239.63000             0.00000
         0           287.70000           239.63000             0.00000
         0           287.70000           259.20000             0.00000
         0           291.60000           259.20000             0.00000
         0           291.60000           383.20000             0.00000
         0           290.20000           383.20000             0.00000
         0           290.20000           397.10000             0.00000
         0           264.50000           397.10000             0.00000
         0           264.50000           384.20000             0.00000
         0           254.50000           384.20000             0.00000
         0           254.50000           397.20000             0.00000
         0           264.50000           397.20000             0.00000
         0           290.20000           397.20000             0.00000
         0           290.20000           409.20000             0.00000
         0           291.60000           409.20000             0.00000
         0           291.60000           421.20000             0.00000
         0           201.00000           421.20000             0.00000
         0           200.00000           420.20000            90.00000
         0           200.00000           374.00000             0.00000
         0           199.00000           373.00000           -90.00000
         0           198.40000           373.00000             0.00000
         0           198.40000           313.00000             0.00000
         0           201.40000           313.00000             0.00000
         0           209.10000           313.00000             0.00000
         0           209.10000           303.60000             0.00000
         0           201.40000           303.60000             0.00000
         0           201.40000           312.90000             0.00000
         0           198.40000           312.90000             0.00000
         0           198.40000           199.80000             0.00000
.END_PLACE_KEEPOUT
.PLACE_KEEPOUT      UNOWNED
TOP 3.50000        
         0           198.40000            48.15000             0.00000
         0           198.40000            30.32000             0.00000
         0           215.63000            30.32000             0.00000
         0           225.03000            30.32000             0.00000
         0           225.03000            22.62000             0.00000
         0           215.63000            22.62000             0.00000
         0           215.63000            30.22000             0.00000
         0           198.40000            30.22000             0.00000
         0           198.40000            21.30000             0.00000
         0           215.63000            21.30000             0.00000
         0           225.03000            21.30000             0.00000
         0           225.03000            13.60000             0.00000
         0           215.63000            13.60000             0.00000
         0           215.63000            21.20000             0.00000
         0           198.40000            21.20000             0.00000
         0           198.40000            19.00000             0.00000
         0           201.40000            19.00000             0.00000
         0           209.10000            19.00000             0.00000
         0           209.10000             9.60000             0.00000
         0           201.40000             9.60000             0.00000
         0           201.40000            18.90000             0.00000
         0           198.40000            18.90000             0.00000
         0           198.40000            -0.00000             0.00000
         0           199.00000             0.00000             0.00000
         0           200.00000            -1.00000           -90.00000
         0           201.00000            -2.00000            90.00000
         0           219.00000            -2.00000             0.00000
         0           220.00000            -3.00000           -90.00000
         0           220.00000           -37.80000             0.00000
         0           221.00000           -38.80000            90.00000
         0           291.60000           -38.80000             0.00000
         0           291.60000            10.20000             0.00000
         0           267.99000            10.20000             0.00000
         0           267.99000             2.60000             0.00000
         0           258.59000             2.60000             0.00000
         0           258.59000            10.30000             0.00000
         0           267.99000            10.30000             0.00000
         0           291.60000            10.30000             0.00000
         0           291.60000            20.20000             0.00000
         0           267.76000            20.20000             0.00000
         0           267.76000            12.60000             0.00000
         0           258.36000            12.60000             0.00000
         0           258.36000            20.30000             0.00000
         0           267.76000            20.30000             0.00000
         0           291.60000            20.30000             0.00000
         0           291.60000            34.40000             0.00000
         0           267.67000            34.40000             0.00000
         0           267.67000            25.10000             0.00000
         0           259.97000            25.10000             0.00000
         0           259.97000            34.50000             0.00000
         0           267.67000            34.50000             0.00000
         0           291.60000            34.50000             0.00000
         0           291.60000            48.15000             0.00000
         0           198.40000            48.15000             0.00000
.END_PLACE_KEEPOUT
.PLACE_KEEPOUT      UNOWNED
TOP 3.50000        
         0           233.60000           143.50000             0.00000
         0           226.10000           143.50000           180.00000
         0           233.60000           143.50000           180.00000
.END_PLACE_KEEPOUT
.PLACE_KEEPOUT      UNOWNED
TOP 3.50000        
         0           251.60000           143.50000             0.00000
         0           244.10000           143.50000           180.00000
         0           251.60000           143.50000           180.00000
.END_PLACE_KEEPOUT
.PLACE_KEEPOUT      UNOWNED
TOP 3.50000        
         0           231.70000           263.20000             0.00000
         0           231.70000           289.20000             0.00000
         0           256.70000           289.20000             0.00000
         0           256.70000           263.20000             0.00000
         0           231.70000           263.20000             0.00000
.END_PLACE_KEEPOUT
.PLACE_KEEPOUT      UNOWNED
TOP 3.50000        
         0           231.70000           350.20000             0.00000
         0           231.70000           376.20000             0.00000
         0           256.70000           376.20000             0.00000
         0           256.70000           350.20000             0.00000
         0           231.70000           350.20000             0.00000
.END_PLACE_KEEPOUT
.PLACE_KEEPOUT      UNOWNED
TOP 3.50000        
         0           284.30000           414.22000             0.00000
         0           276.80000           414.22000           180.00000
         0           284.30000           414.22000           180.00000
.END_PLACE_KEEPOUT
.PLACE_KEEPOUT      UNOWNED
TOP 3.50000        
         0           250.00000            -9.57246             0.00000
         0           250.00000           -24.80000             0.00000
         0           230.00000           -24.80000             0.00000
         0           230.00000           -10.24700             0.00000
         0           226.10000            -6.50000           -92.29244
         0           232.45240            -3.80000          -133.94552
         0           245.24760            -3.80000             0.00000
         0           245.00000            -4.06279             5.51868
         0           251.60000            -6.50000          -139.46420
         0           250.00000            -9.57246           -55.01700
.END_PLACE_KEEPOUT
.PLACE_KEEPOUT      UNOWNED
TOP 0.50000        
         0           198.40000           130.35000             0.00000
         0           198.40000            79.80000             0.00000
         0           214.80000            79.80000             0.00000
         0           214.80000            53.80000             0.00000
         0           198.40000            53.80000             0.00000
         0           198.40000            48.15000             0.00000
         0           291.60000            48.15000             0.00000
         0           291.60000           128.20000             0.00000
         0           287.70000           128.20000             0.00000
         0           287.70000           130.35000             0.00000
         0           198.40000           130.35000             0.00000
.END_PLACE_KEEPOUT
.PLACE_KEEPOUT      UNOWNED
TOP 10.00000       
         0           209.10000           303.60000             0.00000
         0           209.10000           313.00000             0.00000
         0           201.40000           313.00000             0.00000
         0           201.40000           303.60000             0.00000
         0           209.10000           303.60000             0.00000
.END_PLACE_KEEPOUT
.PLACE_KEEPOUT      UNOWNED
TOP 10.00000       
         0           284.70000           230.23000             0.00000
         0           284.70000           239.63000             0.00000
         0           277.00000           239.63000             0.00000
         0           277.00000           230.23000             0.00000
         0           284.70000           230.23000             0.00000
.END_PLACE_KEEPOUT
.PLACE_KEEPOUT      UNOWNED
TOP 10.00000       
         0           289.65000           219.70000             0.00000
         0           289.65000           229.10000             0.00000
         0           281.95000           229.10000             0.00000
         0           281.95000           219.70000             0.00000
         0           289.65000           219.70000             0.00000
.END_PLACE_KEEPOUT
.PLACE_KEEPOUT      UNOWNED
TOP 10.00000       
         0           208.05000           158.30000             0.00000
         0           208.05000           167.70000             0.00000
         0           200.35000           167.70000             0.00000
         0           200.35000           158.30000             0.00000
         0           208.05000           158.30000             0.00000
.END_PLACE_KEEPOUT
.PLACE_KEEPOUT      UNOWNED
TOP 10.00000       
         0           209.10000             9.60000             0.00000
         0           209.10000            19.00000             0.00000
         0           201.40000            19.00000             0.00000
         0           201.40000             9.60000             0.00000
         0           209.10000             9.60000             0.00000
.END_PLACE_KEEPOUT
.PLACE_KEEPOUT      UNOWNED
TOP 10.00000       
         0           225.03000            21.30000             0.00000
         0           215.63000            21.30000             0.00000
         0           215.63000            13.60000             0.00000
         0           225.03000            13.60000             0.00000
         0           225.03000            21.30000             0.00000
.END_PLACE_KEEPOUT
.PLACE_KEEPOUT      UNOWNED
TOP 10.00000       
         0           267.67000            25.10000             0.00000
         0           267.67000            34.50000             0.00000
         0           259.97000            34.50000             0.00000
         0           259.97000            25.10000             0.00000
         0           267.67000            25.10000             0.00000
.END_PLACE_KEEPOUT
.PLACE_KEEPOUT      UNOWNED
TOP 10.00000       
         0           258.36000            20.30000             0.00000
         0           258.36000            12.60000             0.00000
         0           267.76000            12.60000             0.00000
         0           267.76000            20.30000             0.00000
         0           258.36000            20.30000             0.00000
.END_PLACE_KEEPOUT
.PLACE_KEEPOUT      UNOWNED
TOP 10.00000       
         0           258.59000            10.30000             0.00000
         0           258.59000             2.60000             0.00000
         0           267.99000             2.60000             0.00000
         0           267.99000            10.30000             0.00000
         0           258.59000            10.30000             0.00000
.END_PLACE_KEEPOUT
.PLACE_KEEPOUT      UNOWNED
TOP 10.00000       
         0           225.03000            22.62000             0.00000
         0           215.63000            22.62000             0.00000
         0           215.63000            30.32000             0.00000
         0           225.03000            30.32000             0.00000
         0           225.03000            22.62000             0.00000
.END_PLACE_KEEPOUT
.PLACE_KEEPOUT      UNOWNED
TOP 3.80000        
         0           264.50000           384.20000             0.00000
         0           264.50000           397.20000             0.00000
         0           254.50000           397.20000             0.00000
         0           254.50000           384.20000             0.00000
         0           264.50000           384.20000             0.00000
.END_PLACE_KEEPOUT
.PLACE_KEEPOUT      UNOWNED
BOTTOM 0.00000        
         0           209.30000           189.80000             0.00000
         0           209.30000           183.80000             0.00000
         0           195.30000           183.80000          -180.00000
         0           195.30000           189.80000             0.00000
         0           209.30000           189.80000          -180.00000
.END_PLACE_KEEPOUT
.PLACE_KEEPOUT      UNOWNED
BOTTOM 0.00000        
         0           166.32500           207.80000             0.00000
         0           152.32500           207.80000          -180.00000
         0           152.32500           213.80000             0.00000
         0           166.32500           213.80000          -180.00000
         0           166.32500           207.80000             0.00000
.END_PLACE_KEEPOUT
.PLACE_KEEPOUT      UNOWNED
BOTTOM 0.00000        
         0           103.32500           207.80000             0.00000
         0            89.32500           207.80000          -180.00000
         0            89.32500           213.80000             0.00000
         0           103.32500           213.80000          -180.00000
         0           103.32500           207.80000             0.00000
.END_PLACE_KEEPOUT
.PLACE_KEEPOUT      UNOWNED
BOTTOM 0.00000        
         0            40.32500           207.80000             0.00000
         0            26.32500           207.80000          -180.00000
         0            26.32500           213.80000             0.00000
         0            40.32500           213.80000          -180.00000
         0            40.32500           207.80000             0.00000
.END_PLACE_KEEPOUT
.PLACE_KEEPOUT      UNOWNED
BOTTOM 0.00000        
         0            89.32500            92.80000             0.00000
         0            89.32500            98.80000             0.00000
         0           103.32500            98.80000          -180.00000
         0           103.32500            92.80000             0.00000
         0            89.32500            92.80000          -180.00000
.END_PLACE_KEEPOUT
.PLACE_KEEPOUT      UNOWNED
BOTTOM 0.00000        
         0            26.32500            92.80000             0.00000
         0            26.32500            98.80000             0.00000
         0            40.32500            98.80000          -180.00000
         0            40.32500            92.80000             0.00000
         0            26.32500            92.80000          -180.00000
.END_PLACE_KEEPOUT
.PLACE_KEEPOUT      UNOWNED
BOTTOM 0.00000        
         0           195.30000            63.80000             0.00000
         0           195.30000            69.80000             0.00000
         0           209.30000            69.80000          -180.00000
         0           209.30000            63.80000             0.00000
         0           195.30000            63.80000          -180.00000
.END_PLACE_KEEPOUT
.PLACE_KEEPOUT      UNOWNED
BOTTOM 0.00000        
         0           152.32500            92.80000             0.00000
         0           152.32500            98.80000             0.00000
         0           166.32500            98.80000          -180.00000
         0           166.32500            92.80000             0.00000
         0           152.32500            92.80000          -180.00000
.END_PLACE_KEEPOUT
.PLACE_KEEPOUT      UNOWNED
BOTTOM 0.00000        
         0           323.67500            92.80000             0.00000
         0           323.67500            98.80000             0.00000
         0           337.67500            98.80000          -180.00000
         0           337.67500            92.80000             0.00000
         0           323.67500            92.80000          -180.00000
.END_PLACE_KEEPOUT
.PLACE_KEEPOUT      UNOWNED
BOTTOM 0.00000        
         0           293.20000           138.20000             0.00000
         0           293.20000           144.20000             0.00000
         0           307.20000           144.20000          -180.00000
         0           307.20000           138.20000             0.00000
         0           293.20000           138.20000          -180.00000
.END_PLACE_KEEPOUT
.PLACE_KEEPOUT      UNOWNED
BOTTOM 0.00000        
         0           449.67500            92.80000             0.00000
         0           449.67500            98.80000             0.00000
         0           463.67500            98.80000          -180.00000
         0           463.67500            92.80000             0.00000
         0           449.67500            92.80000          -180.00000
.END_PLACE_KEEPOUT
.PLACE_KEEPOUT      UNOWNED
BOTTOM 0.00000        
         0           386.67500            92.80000             0.00000
         0           386.67500            98.80000             0.00000
         0           400.67500            98.80000          -180.00000
         0           400.67500            92.80000             0.00000
         0           386.67500            92.80000          -180.00000
.END_PLACE_KEEPOUT
.PLACE_KEEPOUT      UNOWNED
BOTTOM 0.00000        
         0           449.67500           207.80000             0.00000
         0           449.67500           213.80000             0.00000
         0           463.67500           213.80000          -180.00000
         0           463.67500           207.80000             0.00000
         0           449.67500           207.80000          -180.00000
.END_PLACE_KEEPOUT
.PLACE_KEEPOUT      UNOWNED
BOTTOM 0.00000        
         0           386.67500           207.80000             0.00000
         0           386.67500           213.80000             0.00000
         0           400.67500           213.80000          -180.00000
         0           400.67500           207.80000             0.00000
         0           386.67500           207.80000          -180.00000
.END_PLACE_KEEPOUT
.PLACE_KEEPOUT      UNOWNED
BOTTOM 0.00000        
         0           323.67500           207.80000             0.00000
         0           323.67500           213.80000             0.00000
         0           337.67500           213.80000          -180.00000
         0           337.67500           207.80000             0.00000
         0           323.67500           207.80000          -180.00000
.END_PLACE_KEEPOUT
.PLACE_KEEPOUT      UNOWNED
BOTTOM 0.00000        
         0           293.20000           243.20000             0.00000
         0           293.20000           249.20000             0.00000
         0           307.20000           249.20000          -180.00000
         0           307.20000           243.20000             0.00000
         0           293.20000           243.20000          -180.00000
.END_PLACE_KEEPOUT
.PLACE_KEEPOUT      UNOWNED
BOTTOM 0.00000        
         0           237.20000           273.20000             0.00000
         0           237.20000           279.20000             0.00000
         0           251.20000           279.20000          -180.00000
         0           251.20000           273.20000             0.00000
         0           237.20000           273.20000          -180.00000
.END_PLACE_KEEPOUT
.PLACE_KEEPOUT      UNOWNED
BOTTOM 0.00000        
         0           386.67500           322.80000             0.00000
         0           386.67500           328.80000             0.00000
         0           400.67500           328.80000          -180.00000
         0           400.67500           322.80000             0.00000
         0           386.67500           322.80000          -180.00000
.END_PLACE_KEEPOUT
.PLACE_KEEPOUT      UNOWNED
BOTTOM 0.00000        
         0           323.67500           322.80000             0.00000
         0           323.67500           328.80000             0.00000
         0           337.67500           328.80000          -180.00000
         0           337.67500           322.80000             0.00000
         0           323.67500           322.80000          -180.00000
.END_PLACE_KEEPOUT
.PLACE_KEEPOUT      UNOWNED
BOTTOM 0.00000        
         0           449.67500           322.80000             0.00000
         0           449.67500           328.80000             0.00000
         0           463.67500           328.80000          -180.00000
         0           463.67500           322.80000             0.00000
         0           449.67500           322.80000          -180.00000
.END_PLACE_KEEPOUT
.PLACE_KEEPOUT      UNOWNED
BOTTOM 0.00000        
         0           293.20000           393.20000             0.00000
         0           293.20000           399.20000             0.00000
         0           307.20000           399.20000          -180.00000
         0           307.20000           393.20000             0.00000
         0           293.20000           393.20000          -180.00000
.END_PLACE_KEEPOUT
.PLACE_KEEPOUT      UNOWNED
BOTTOM 0.00000        
         0           237.20000           360.20000             0.00000
         0           237.20000           366.20000             0.00000
         0           251.20000           366.20000          -180.00000
         0           251.20000           360.20000             0.00000
         0           237.20000           360.20000          -180.00000
.END_PLACE_KEEPOUT
.PLACE_KEEPOUT      UNOWNED
BOTTOM 0.00000        
         0           152.32500           322.80000             0.00000
         0           152.32500           328.80000             0.00000
         0           166.32500           328.80000          -180.00000
         0           166.32500           322.80000             0.00000
         0           152.32500           322.80000          -180.00000
.END_PLACE_KEEPOUT
.PLACE_KEEPOUT      UNOWNED
BOTTOM 0.00000        
         0            89.32500           322.80000             0.00000
         0            89.32500           328.80000             0.00000
         0           103.32500           328.80000          -180.00000
         0           103.32500           322.80000             0.00000
         0            89.32500           322.80000          -180.00000
.END_PLACE_KEEPOUT
.PLACE_KEEPOUT      UNOWNED
BOTTOM 0.00000        
         0            26.32500           322.80000             0.00000
         0            26.32500           328.80000             0.00000
         0            40.32500           328.80000          -180.00000
         0            40.32500           322.80000             0.00000
         0            26.32500           322.80000          -180.00000
.END_PLACE_KEEPOUT
.PLACE_KEEPOUT      UNOWNED
BOTTOM 0.00000        
         0           178.65000           208.50000             0.00000
         0           186.15000           208.50000          -180.00000
         0           178.65000           208.50000          -180.00000
.END_PLACE_KEEPOUT
.PLACE_KEEPOUT      UNOWNED
BOTTOM 0.00000        
         0           367.85000           220.20000             0.00000
         0           375.35000           220.20000          -180.00000
         0           367.85000           220.20000          -180.00000
.END_PLACE_KEEPOUT
.PLACE_KEEPOUT      UNOWNED
BOTTOM 0.00000        
         0           251.60000           143.50000             0.00000
         0           244.10000           143.50000          -180.00000
         0           251.60000           143.50000          -180.00000
.END_PLACE_KEEPOUT
.PLACE_KEEPOUT      UNOWNED
BOTTOM 0.00000        
         0           233.60000           143.50000             0.00000
         0           226.10000           143.50000          -180.00000
         0           233.60000           143.50000          -180.00000
.END_PLACE_KEEPOUT
.PLACE_KEEPOUT      UNOWNED
BOTTOM 0.00000        
         0             7.60000           120.50000             0.00000
         0             0.10000           120.50000          -180.00000
         0             7.60000           120.50000          -180.00000
.END_PLACE_KEEPOUT
.PLACE_KEEPOUT      UNOWNED
BOTTOM 0.00000        
         0             7.60000             5.50000             0.00000
         0             0.10000             5.50000          -180.00000
         0             7.60000             5.50000          -180.00000
.END_PLACE_KEEPOUT
.PLACE_KEEPOUT      UNOWNED
BOTTOM 0.00000        
         0           251.60000            -6.50000             0.00000
         0           244.10000            -6.50000          -180.00000
         0           251.60000            -6.50000          -180.00000
.END_PLACE_KEEPOUT
.PLACE_KEEPOUT      UNOWNED
BOTTOM 0.00000        
         0           233.60000            -6.50000             0.00000
         0           226.10000            -6.50000          -180.00000
         0           233.60000            -6.50000          -180.00000
.END_PLACE_KEEPOUT
.PLACE_KEEPOUT      UNOWNED
BOTTOM 0.00000        
         0           485.00000             5.50000             0.00000
         0           477.50000             5.50000          -180.00000
         0           485.00000             5.50000          -180.00000
.END_PLACE_KEEPOUT
.PLACE_KEEPOUT      UNOWNED
BOTTOM 0.00000        
         0           485.00000           120.50000             0.00000
         0           477.50000           120.50000          -180.00000
         0           485.00000           120.50000          -180.00000
.END_PLACE_KEEPOUT
.PLACE_KEEPOUT      UNOWNED
BOTTOM 0.00000        
         0           468.42500             9.20000             0.00000
         0           458.92500             9.20000          -180.00000
         0           468.42500             9.20000          -180.00000
.END_PLACE_KEEPOUT
.PLACE_KEEPOUT      UNOWNED
BOTTOM 0.00000        
         0           328.42500             9.20000             0.00000
         0           318.92500             9.20000          -180.00000
         0           328.42500             9.20000          -180.00000
.END_PLACE_KEEPOUT
.PLACE_KEEPOUT      UNOWNED
BOTTOM 0.00000        
         0           171.07500             9.20000             0.00000
         0           161.57500             9.20000          -180.00000
         0           171.07500             9.20000          -180.00000
.END_PLACE_KEEPOUT
.PLACE_KEEPOUT      UNOWNED
BOTTOM 0.00000        
         0            31.07500             9.20000             0.00000
         0            21.57500             9.20000          -180.00000
         0            31.07500             9.20000          -180.00000
.END_PLACE_KEEPOUT
.PLACE_KEEPOUT      UNOWNED
BOTTOM 0.00000        
         0           174.95000           270.00000             0.00000
         0           165.45000           270.00000          -180.00000
         0           174.95000           270.00000          -180.00000
.END_PLACE_KEEPOUT
.PLACE_KEEPOUT      UNOWNED
BOTTOM 0.00000        
         0           111.85000           290.00000             0.00000
         0           102.35000           290.00000          -180.00000
         0           111.85000           290.00000          -180.00000
.END_PLACE_KEEPOUT
.PLACE_KEEPOUT      UNOWNED
BOTTOM 0.00000        
         0            48.75000           270.00000             0.00000
         0            39.25000           270.00000          -180.00000
         0            48.75000           270.00000          -180.00000
.END_PLACE_KEEPOUT
.PLACE_KEEPOUT      UNOWNED
BOTTOM 0.00000        
         0           346.05000           270.00000             0.00000
         0           336.55000           270.00000          -180.00000
         0           346.05000           270.00000          -180.00000
.END_PLACE_KEEPOUT
.PLACE_KEEPOUT      UNOWNED
BOTTOM 0.00000        
         0           472.25000           270.00000             0.00000
         0           462.75000           270.00000          -180.00000
         0           472.25000           270.00000          -180.00000
.END_PLACE_KEEPOUT
.PLACE_KEEPOUT      UNOWNED
BOTTOM 0.00000        
         0           409.15000           290.00000             0.00000
         0           399.65000           290.00000          -180.00000
         0           409.15000           290.00000          -180.00000
.END_PLACE_KEEPOUT
.PLACE_KEEPOUT      UNOWNED
BOTTOM 0.00000        
         0           284.30000           414.22000             0.00000
         0           276.80000           414.22000          -180.00000
         0           284.30000           414.22000          -180.00000
.END_PLACE_KEEPOUT
.PLACE_KEEPOUT      UNOWNED
BOTTOM 0.00000        
         0           410.85000           164.20000             0.00000
         0           403.35000           164.20000          -180.00000
         0           410.85000           164.20000          -180.00000
.END_PLACE_KEEPOUT
.PLACE_KEEPOUT      UNOWNED
BOTTOM 0.00000        
         0           350.75000           164.20000             0.00000
         0           343.25000           164.20000          -180.00000
         0           350.75000           164.20000          -180.00000
.END_PLACE_KEEPOUT
.PLACE_KEEPOUT      UNOWNED
BOTTOM 0.00000        
         0           171.45000           164.20000             0.00000
         0           163.95000           164.20000          -180.00000
         0           171.45000           164.20000          -180.00000
.END_PLACE_KEEPOUT
.PLACE_KEEPOUT      UNOWNED
BOTTOM 0.00000        
         0            46.50000           164.20000             0.00000
         0            39.00000           164.20000          -180.00000
         0            46.50000           164.20000          -180.00000
.END_PLACE_KEEPOUT
.PLACE_KEEPOUT      UNOWNED
BOTTOM 0.00000        
         0            11.75000           224.20000             0.00000
         0             4.25000           224.20000          -180.00000
         0            11.75000           224.20000          -180.00000
.END_PLACE_KEEPOUT
.PLACE_KEEPOUT      UNOWNED
BOTTOM 0.00000        
         0           487.20000           204.20000             0.00000
         0           479.70000           204.20000          -180.00000
         0           487.20000           204.20000          -180.00000
.END_PLACE_KEEPOUT
.PLACE_KEEPOUT      UNOWNED
BOTTOM 0.00000        
         0           103.32500           207.80000             0.00000
         0           103.32500           213.80000             0.00000
         0           101.04362           218.97055            47.61655
         0           154.60638           218.97055          -146.06786
         0           152.32500           213.80000            47.61655
         0           152.32500           207.80000             0.00000
         0           154.60638           202.62945            47.61655
         0           101.04362           202.62945          -146.06786
         0           103.32500           207.80000            47.61655
.END_PLACE_KEEPOUT
.PLACE_KEEPOUT      UNOWNED
BOTTOM 0.00000        
         0           400.67500           207.80000             0.00000
         0           400.67500           213.80000             0.00000
         0           398.39362           218.97055            47.61655
         0           451.95638           218.97055          -146.06786
         0           449.67500           213.80000            47.61655
         0           449.67500           207.80000             0.00000
         0           451.95638           202.62945            47.61655
         0           398.39362           202.62945          -146.06786
         0           400.67500           207.80000            47.61655
.END_PLACE_KEEPOUT
.PLACE_KEEPOUT      UNOWNED
BOTTOM 2.00000        
         0            87.82500           210.80000             0.00000
         0           167.82500           210.80000          -180.00000
         0            87.82500           210.80000          -180.00000
.END_PLACE_KEEPOUT
.PLACE_KEEPOUT      UNOWNED
BOTTOM 2.00000        
         0           465.17500           210.80000             0.00000
         0           385.17500           210.80000          -180.00000
         0           465.17500           210.80000          -180.00000
.END_PLACE_KEEPOUT
.PLACE_KEEPOUT      UNOWNED
BOTTOM 2.00000        
         0           386.67500           213.80000             0.00000
         0           398.39362           218.97055          -132.38345
         0           451.95638           218.97055          -146.06786
         0           463.67500           213.80000          -132.38345
         0           463.67500           207.80000             0.00000
         0           451.95638           202.62945          -132.38345
         0           398.39362           202.62945          -146.06786
         0           386.67500           207.80000          -132.38345
         0           386.67500           213.80000             0.00000
.END_PLACE_KEEPOUT
.PLACE_KEEPOUT      UNOWNED
BOTTOM 2.00000        
         0            89.32500           213.80000             0.00000
         0           101.04362           218.97055          -132.38345
         0           154.60638           218.97055          -146.06786
         0           166.32500           213.80000          -132.38345
         0           166.32500           207.80000             0.00000
         0           154.60638           202.62945          -132.38345
         0           101.04362           202.62945          -146.06786
         0            89.32500           207.80000          -132.38345
         0            89.32500           213.80000             0.00000
.END_PLACE_KEEPOUT
.PLACE_KEEPOUT      UNOWNED
BOTTOM 0.00000        
         0           487.20000           204.20000             0.00000
         0           479.70000           204.20000          -180.00000
         0           487.20000           204.20000          -180.00000
.END_PLACE_KEEPOUT
.PLACE_KEEPOUT      UNOWNED
BOTTOM 0.00000        
         0           200.00000           301.00000             0.00000
         0           200.00000           259.00000             0.00000
         0             0.00000           259.00000             0.00000
         0             0.00000           301.00000             0.00000
         0           200.00000           301.00000             0.00000
.END_PLACE_KEEPOUT
.PLACE_KEEPOUT      UNOWNED
BOTTOM 0.00000        
         0           491.45000           301.00000             0.00000
         0           290.00000           301.00000             0.00000
         0           290.00000           259.00000             0.00000
         0           491.45000           259.00000             0.00000
         0           491.45000           301.00000             0.00000
.END_PLACE_KEEPOUT
.PLACE_KEEPOUT      UNOWNED
BOTTOM 0.00000        
         0             0.00000             1.00000             0.00000
         0             0.00000           209.20000             0.00000
         0            13.85000           209.20000             0.00000
         0            13.85000             0.00000             0.00000
         0             1.00000             0.00000             0.00000
         0             0.00000             1.00000           -90.00000
.END_PLACE_KEEPOUT
.PLACE_KEEPOUT      UNOWNED
BOTTOM 0.00000        
         0           251.85000           209.20000             0.00000
         0           225.85000           209.20000             0.00000
         0           225.85000           -38.80000             0.00000
         0           251.85000           -38.80000             0.00000
         0           251.85000           209.20000             0.00000
.END_PLACE_KEEPOUT
.PLACE_KEEPOUT      UNOWNED
BOTTOM 0.00000        
         0           491.45000           209.20000             0.00000
         0           491.45000             1.00000             0.00000
         0           490.45000             0.00000           -90.00000
         0           476.25000             0.00000             0.00000
         0           476.25000           209.20000             0.00000
         0           491.45000           209.20000             0.00000
.END_PLACE_KEEPOUT
.PLACE_KEEPOUT      UNOWNED
BOTTOM 0.00000        
         0           462.75000           270.00000             0.00000
         0           472.25000           270.00000          -180.00000
         0           462.75000           270.00000          -180.00000
.END_PLACE_KEEPOUT
.PLACE_KEEPOUT      UNOWNED
BOTTOM 0.00000        
         0           399.65000           290.00000             0.00000
         0           409.15000           290.00000          -180.00000
         0           399.65000           290.00000          -180.00000
.END_PLACE_KEEPOUT
.PLACE_KEEPOUT      UNOWNED
BOTTOM 0.00000        
         0           336.55000           270.00000             0.00000
         0           346.05000           270.00000          -180.00000
         0           336.55000           270.00000          -180.00000
.END_PLACE_KEEPOUT
.PLACE_KEEPOUT      UNOWNED
BOTTOM 0.00000        
         0           165.45000           270.00000             0.00000
         0           174.95000           270.00000          -180.00000
         0           165.45000           270.00000          -180.00000
.END_PLACE_KEEPOUT
.PLACE_KEEPOUT      UNOWNED
BOTTOM 0.00000        
         0           102.35000           290.00000             0.00000
         0           111.85000           290.00000          -180.00000
         0           102.35000           290.00000          -180.00000
.END_PLACE_KEEPOUT
.PLACE_KEEPOUT      UNOWNED
BOTTOM 0.00000        
         0            39.25000           270.00000             0.00000
         0            48.75000           270.00000          -180.00000
         0            39.25000           270.00000          -180.00000
.END_PLACE_KEEPOUT
.PLACE_KEEPOUT      UNOWNED
BOTTOM 0.00000        
         0             0.10000           120.50000             0.00000
         0             7.60000           120.50000          -180.00000
         0             0.10000           120.50000          -180.00000
.END_PLACE_KEEPOUT
.PLACE_KEEPOUT      UNOWNED
BOTTOM 0.00000        
         0             7.60000             5.50000             0.00000
         0             0.10000             5.50000          -180.00000
         0             7.60000             5.50000          -180.00000
.END_PLACE_KEEPOUT
.PLACE_KEEPOUT      UNOWNED
BOTTOM 0.00000        
         0           233.60000           143.50000             0.00000
         0           226.10000           143.50000          -180.00000
         0           233.60000           143.50000          -180.00000
.END_PLACE_KEEPOUT
.PLACE_KEEPOUT      UNOWNED
BOTTOM 0.00000        
         0           251.60000           143.50000             0.00000
         0           244.10000           143.50000          -180.00000
         0           251.60000           143.50000          -180.00000
.END_PLACE_KEEPOUT
.PLACE_KEEPOUT      UNOWNED
BOTTOM 0.00000        
         0           245.24760            -3.80000             0.00000
         0           251.60000            -6.50000          -133.94552
         0           250.00000            -9.57246           -55.01700
         0           250.00000           -24.80000             0.00000
         0           230.00000           -24.80000             0.00000
         0           230.00000           -10.24700             0.00000
         0           226.10000            -6.50000           -92.29244
         0           232.45240            -3.80000          -133.94552
         0           245.24760            -3.80000             0.00000
.END_PLACE_KEEPOUT
.PLACE_KEEPOUT      UNOWNED
BOTTOM 0.00000        
         0           477.50000           120.50000             0.00000
         0           485.00000           120.50000          -180.00000
         0           477.50000           120.50000          -180.00000
.END_PLACE_KEEPOUT
.PLACE_KEEPOUT      UNOWNED
BOTTOM 0.00000        
         0           477.50000             5.50000             0.00000
         0           485.00000             5.50000          -180.00000
         0           477.50000             5.50000          -180.00000
.END_PLACE_KEEPOUT
.PLACE_KEEPOUT      UNOWNED
BOTTOM 0.20000        
         0           251.85000           -38.80000             0.00000
         0           251.85000            99.20000             0.00000
         0           281.85000            99.20000             0.00000
         0           281.85000           135.36000             0.00000
         0           293.80200           135.36000             0.00000
         0           306.59800           135.36000           132.12821
         0           392.35000           135.36000             0.00000
         0           392.35000           149.20000             0.00000
         0           476.25000           149.20000             0.00000
         0           476.25000            -0.00000             0.00000
         0           397.00000             0.00000             0.00000
         0           396.00000             1.00000           -90.00000
         0           396.00000            14.00000             0.00000
         0           395.00000            15.00000            90.00000
         0           349.00000            15.00000             0.00000
         0           348.00000            14.00000            90.00000
         0           348.00000             1.00000             0.00000
         0           347.00000             0.00000           -90.00000
         0           301.00000             0.00000             0.00000
         0           300.00000            -1.00000            90.00000
         0           300.00000           -37.80000             0.00000
         0           299.00000           -38.80000           -90.00000
         0           251.85000           -38.80000             0.00000
.END_PLACE_KEEPOUT
.PLACE_KEEPOUT      UNOWNED
BOTTOM 0.20000        
         0            13.85000            -0.00000             0.00000
         0            13.85000           134.20000             0.00000
         0           146.35000           134.20000             0.00000
         0           146.35000           149.20000             0.00000
         0           215.35000           149.20000             0.00000
         0           215.35000            99.20000             0.00000
         0           225.85000            99.20000             0.00000
         0           225.85000           -38.80000             0.00000
         0           221.00000           -38.80000             0.00000
         0           220.00000           -37.80000           -90.00000
         0           220.00000            -3.00000             0.00000
         0           219.00000            -2.00000            90.00000
         0           201.00000            -2.00000             0.00000
         0           200.00000            -1.00000           -90.00000
         0           199.00000             0.00000            90.00000
         0           151.00000             0.00000             0.00000
         0           150.00000             1.00000           -90.00000
         0           150.00000            14.00000             0.00000
         0           149.00000            15.00000            90.00000
         0           103.00000            15.00000             0.00000
         0           102.00000            14.00000            90.00000
         0           102.00000             1.00000             0.00000
         0           101.00000             0.00000           -90.00000
         0            13.85000            -0.00000             0.00000
.END_PLACE_KEEPOUT
.PLACE_KEEPOUT      UNOWNED
BOTTOM 0.20000        
         0           166.32500            92.80000             0.00000
         0           152.32500            92.80000          -180.00000
         0           152.32500            98.80000             0.00000
         0           166.32500            98.80000          -180.00000
         0           166.32500            92.80000             0.00000
.END_PLACE_KEEPOUT
.PLACE_KEEPOUT      UNOWNED
BOTTOM 0.20000        
         0           103.32500            92.80000             0.00000
         0            89.32500            92.80000          -180.00000
         0            89.32500            98.80000             0.00000
         0           103.32500            98.80000          -180.00000
         0           103.32500            92.80000             0.00000
.END_PLACE_KEEPOUT
.PLACE_KEEPOUT      UNOWNED
BOTTOM 0.20000        
         0           209.30000            63.80000             0.00000
         0           195.30000            63.80000          -180.00000
         0           195.30000            69.80000             0.00000
         0           209.30000            69.80000          -180.00000
         0           209.30000            63.80000             0.00000
.END_PLACE_KEEPOUT
.PLACE_KEEPOUT      UNOWNED
BOTTOM 0.20000        
         0            40.32500            92.80000             0.00000
         0            26.32500            92.80000          -180.00000
         0            26.32500            98.80000             0.00000
         0            40.32500            98.80000          -180.00000
         0            40.32500            92.80000             0.00000
.END_PLACE_KEEPOUT
.PLACE_KEEPOUT      UNOWNED
BOTTOM 0.20000        
         0            21.57500             9.20000             0.00000
         0            31.07500             9.20000          -180.00000
         0            21.57500             9.20000          -180.00000
.END_PLACE_KEEPOUT
.PLACE_KEEPOUT      UNOWNED
BOTTOM 0.20000        
         0           161.57500             9.20000             0.00000
         0           171.07500             9.20000          -180.00000
         0           161.57500             9.20000          -180.00000
.END_PLACE_KEEPOUT
.PLACE_KEEPOUT      UNOWNED
BOTTOM 0.20000        
         0           337.67500            92.80000             0.00000
         0           323.67500            92.80000          -180.00000
         0           323.67500            98.80000             0.00000
         0           337.67500            98.80000          -180.00000
         0           337.67500            92.80000             0.00000
.END_PLACE_KEEPOUT
.PLACE_KEEPOUT      UNOWNED
BOTTOM 0.20000        
         0           400.67500            92.80000             0.00000
         0           386.67500            92.80000          -180.00000
         0           386.67500            98.80000             0.00000
         0           400.67500            98.80000          -180.00000
         0           400.67500            92.80000             0.00000
.END_PLACE_KEEPOUT
.PLACE_KEEPOUT      UNOWNED
BOTTOM 0.20000        
         0           463.67500            92.80000             0.00000
         0           449.67500            92.80000          -180.00000
         0           449.67500            98.80000             0.00000
         0           463.67500            98.80000          -180.00000
         0           463.67500            92.80000             0.00000
.END_PLACE_KEEPOUT
.PLACE_KEEPOUT      UNOWNED
BOTTOM 0.20000        
         0           458.92500             9.20000             0.00000
         0           468.42500             9.20000          -180.00000
         0           458.92500             9.20000          -180.00000
.END_PLACE_KEEPOUT
.PLACE_KEEPOUT      UNOWNED
BOTTOM 0.20000        
         0           318.92500             9.20000             0.00000
         0           328.42500             9.20000          -180.00000
         0           318.92500             9.20000          -180.00000
.END_PLACE_KEEPOUT
.PLACE_KEEPOUT      UNOWNED
BOTTOM 0.20000        
         0           456.57500            13.20000             0.00000
         0           458.77500            13.20000          -180.00000
         0           456.57500            13.20000          -180.00000
.END_PLACE_KEEPOUT
.PLACE_KEEPOUT      UNOWNED
BOTTOM 0.20000        
         0           468.57500             5.20000             0.00000
         0           470.77500             5.20000          -180.00000
         0           468.57500             5.20000          -180.00000
.END_PLACE_KEEPOUT
.PLACE_KEEPOUT      UNOWNED
BOTTOM 0.20000        
         0           370.94500            20.55000             0.00000
         0           373.35500            20.55000          -180.00000
         0           370.94500            20.55000          -180.00000
.END_PLACE_KEEPOUT
.PLACE_KEEPOUT      UNOWNED
BOTTOM 0.20000        
         0           370.87500            28.08000             0.00000
         0           373.42500            28.08000          -180.00000
         0           370.87500            28.08000          -180.00000
.END_PLACE_KEEPOUT
.PLACE_KEEPOUT      UNOWNED
BOTTOM 0.20000        
         0           328.57500             5.20000             0.00000
         0           330.77500             5.20000          -180.00000
         0           328.57500             5.20000          -180.00000
.END_PLACE_KEEPOUT
.PLACE_KEEPOUT      UNOWNED
BOTTOM 0.20000        
         0           316.57500            13.20000             0.00000
         0           318.77500            13.20000          -180.00000
         0           316.57500            13.20000          -180.00000
.END_PLACE_KEEPOUT
.PLACE_KEEPOUT      UNOWNED
BOTTOM 0.20000        
         0           171.22500             5.20000             0.00000
         0           173.42500             5.20000          -180.00000
         0           171.22500             5.20000          -180.00000
.END_PLACE_KEEPOUT
.PLACE_KEEPOUT      UNOWNED
BOTTOM 0.20000        
         0           159.22500            13.20000             0.00000
         0           161.42500            13.20000          -180.00000
         0           159.22500            13.20000          -180.00000
.END_PLACE_KEEPOUT
.PLACE_KEEPOUT      UNOWNED
BOTTOM 0.20000        
         0           124.87500            28.08000             0.00000
         0           127.42500            28.08000          -180.00000
         0           124.87500            28.08000          -180.00000
.END_PLACE_KEEPOUT
.PLACE_KEEPOUT      UNOWNED
BOTTOM 0.20000        
         0           127.35500            20.55000             0.00000
         0           124.94500            20.55000          -180.00000
         0           127.35500            20.55000          -180.00000
.END_PLACE_KEEPOUT
.PLACE_KEEPOUT      UNOWNED
BOTTOM 0.20000        
         0            19.22500            13.20000             0.00000
         0            21.42500            13.20000          -180.00000
         0            19.22500            13.20000          -180.00000
.END_PLACE_KEEPOUT
.PLACE_KEEPOUT      UNOWNED
BOTTOM 0.20000        
         0            31.22500             5.20000             0.00000
         0            33.42500             5.20000          -180.00000
         0            31.22500             5.20000          -180.00000
.END_PLACE_KEEPOUT
.PLACE_KEEPOUT      UNOWNED
BOTTOM 3.10000        
         0           375.35000           220.20000             0.00000
         0           367.85000           220.20000          -180.00000
         0           375.35000           220.20000          -180.00000
.END_PLACE_KEEPOUT
.PLACE_KEEPOUT      UNOWNED
BOTTOM 3.10000        
         0           186.15000           208.50000             0.00000
         0           178.65000           208.50000          -180.00000
         0           186.15000           208.50000          -180.00000
.END_PLACE_KEEPOUT
.PLACE_KEEPOUT      UNOWNED
BOTTOM 3.10000        
         0            13.85000           209.20000             0.00000
         0             0.00000           209.20000             0.00000
         0             0.00000           259.00000             0.00000
         0           200.00000           259.00000             0.00000
         0           200.00000           301.00000             0.00000
         0             0.00000           301.00000             0.00000
         0             0.00000           348.20000             0.00000
         0             1.00000           349.20000           -90.00000
         0           189.70000           349.20000             0.00000
         0           190.70000           350.20000            90.00000
         0           190.70000           372.00000             0.00000
         0           191.70000           373.00000           -90.00000
         0           199.00000           373.00000             0.00000
         0           200.00000           374.00000            90.00000
         0           200.00000           420.20000             0.00000
         0           201.00000           421.20000           -90.00000
         0           309.00000           421.20000             0.00000
         0           310.00000           420.20000           -90.00000
         0           310.00000           375.00000             0.00000
         0           309.00000           374.00000           -90.00000
         0           296.70000           374.00000             0.00000
         0           295.70000           373.00000            90.00000
         0           295.70000           350.20000             0.00000
         0           296.70000           349.20000            90.00000
         0           490.45000           349.20000             0.00000
         0           491.45000           348.20000           -90.00000
         0           491.45000           301.00000             0.00000
         0           290.00000           301.00000             0.00000
         0           290.00000           259.00000             0.00000
         0           491.45000           259.00000             0.00000
         0           491.45000           209.20000             0.00000
         0           476.25000           209.20000             0.00000
         0           476.25000           149.20000             0.00000
         0           392.35000           149.20000             0.00000
         0           392.35000           135.36000             0.00000
         0           306.59800           135.36000             0.00000
         0           307.20000           138.20000            23.93590
         0           307.20000           144.20000             0.00000
         0           293.20000           144.20000           180.00000
         0           293.20000           138.20000             0.00000
         0           293.80200           135.36000            23.93590
         0           281.85000           135.36000             0.00000
         0           281.85000            99.20000             0.00000
         0           251.85000            99.20000             0.00000
         0           251.85000           209.20000             0.00000
         0           225.85000           209.20000             0.00000
         0           225.85000            99.20000             0.00000
         0           215.35000            99.20000             0.00000
         0           215.35000           149.20000             0.00000
         0           146.35000           149.20000             0.00000
         0           146.35000           134.20000             0.00000
         0            13.85000           134.20000             0.00000
         0            13.85000           209.20000             0.00000
.END_PLACE_KEEPOUT
.PLACE_KEEPOUT      UNOWNED
BOTTOM 3.10000        
         0           337.67500           322.80000             0.00000
         0           323.67500           322.80000          -180.00000
         0           323.67500           328.80000             0.00000
         0           337.67500           328.80000          -180.00000
         0           337.67500           322.80000             0.00000
.END_PLACE_KEEPOUT
.PLACE_KEEPOUT      UNOWNED
BOTTOM 3.10000        
         0           307.20000           393.20000             0.00000
         0           293.20000           393.20000          -180.00000
         0           293.20000           399.20000             0.00000
         0           307.20000           399.20000          -180.00000
         0           307.20000           393.20000             0.00000
.END_PLACE_KEEPOUT
.PLACE_KEEPOUT      UNOWNED
BOTTOM 3.10000        
         0           251.20000           360.20000             0.00000
         0           237.20000           360.20000          -180.00000
         0           237.20000           366.20000             0.00000
         0           251.20000           366.20000          -180.00000
         0           251.20000           360.20000             0.00000
.END_PLACE_KEEPOUT
.PLACE_KEEPOUT      UNOWNED
BOTTOM 3.10000        
         0           166.32500           322.80000             0.00000
         0           152.32500           322.80000          -180.00000
         0           152.32500           328.80000             0.00000
         0           166.32500           328.80000          -180.00000
         0           166.32500           322.80000             0.00000
.END_PLACE_KEEPOUT
.PLACE_KEEPOUT      UNOWNED
BOTTOM 3.10000        
         0           103.32500           322.80000             0.00000
         0            89.32500           322.80000          -180.00000
         0            89.32500           328.80000             0.00000
         0           103.32500           328.80000          -180.00000
         0           103.32500           322.80000             0.00000
.END_PLACE_KEEPOUT
.PLACE_KEEPOUT      UNOWNED
BOTTOM 3.10000        
         0            40.32500           322.80000             0.00000
         0            26.32500           322.80000          -180.00000
         0            26.32500           328.80000             0.00000
         0            40.32500           328.80000          -180.00000
         0            40.32500           322.80000             0.00000
.END_PLACE_KEEPOUT
.PLACE_KEEPOUT      UNOWNED
BOTTOM 3.10000        
         0            40.32500           207.80000             0.00000
         0            26.32500           207.80000          -180.00000
         0            26.32500           213.80000             0.00000
         0            40.32500           213.80000          -180.00000
         0            40.32500           207.80000             0.00000
.END_PLACE_KEEPOUT
.PLACE_KEEPOUT      UNOWNED
BOTTOM 3.10000        
         0           209.30000           183.80000             0.00000
         0           195.30000           183.80000          -180.00000
         0           195.30000           189.80000             0.00000
         0           209.30000           189.80000          -180.00000
         0           209.30000           183.80000             0.00000
.END_PLACE_KEEPOUT
.PLACE_KEEPOUT      UNOWNED
BOTTOM 3.10000        
         0           251.20000           273.20000             0.00000
         0           237.20000           273.20000          -180.00000
         0           237.20000           279.20000             0.00000
         0           251.20000           279.20000          -180.00000
         0           251.20000           273.20000             0.00000
.END_PLACE_KEEPOUT
.PLACE_KEEPOUT      UNOWNED
BOTTOM 3.10000        
         0           307.20000           243.20000             0.00000
         0           293.20000           243.20000          -180.00000
         0           293.20000           249.20000             0.00000
         0           307.20000           249.20000          -180.00000
         0           307.20000           243.20000             0.00000
.END_PLACE_KEEPOUT
.PLACE_KEEPOUT      UNOWNED
BOTTOM 3.10000        
         0           337.67500           207.80000             0.00000
         0           323.67500           207.80000          -180.00000
         0           323.67500           213.80000             0.00000
         0           337.67500           213.80000          -180.00000
         0           337.67500           207.80000             0.00000
.END_PLACE_KEEPOUT
.PLACE_KEEPOUT      UNOWNED
BOTTOM 3.10000        
         0           400.67500           322.80000             0.00000
         0           400.67500           328.80000             0.00000
         0           386.67500           328.80000           180.00000
         0           386.67500           322.80000             0.00000
         0           400.67500           322.80000           180.00000
.END_PLACE_KEEPOUT
.PLACE_KEEPOUT      UNOWNED
BOTTOM 3.10000        
         0           463.67500           322.80000             0.00000
         0           463.67500           328.80000             0.00000
         0           449.67500           328.80000           180.00000
         0           449.67500           322.80000             0.00000
         0           463.67500           322.80000           180.00000
.END_PLACE_KEEPOUT
.PLACE_KEEPOUT      UNOWNED
BOTTOM 3.10000        
         0           276.80000           414.22000             0.00000
         0           284.30000           414.22000          -180.00000
         0           276.80000           414.22000          -180.00000
.END_PLACE_KEEPOUT
.PLACE_KEEPOUT      UNOWNED
BOTTOM 3.10000        
         0             4.25000           224.20000             0.00000
         0            11.75000           224.20000          -180.00000
         0             4.25000           224.20000          -180.00000
.END_PLACE_KEEPOUT
.PLACE_KEEPOUT      UNOWNED
BOTTOM 3.10000        
         0           343.25000           164.20000             0.00000
         0           350.75000           164.20000          -180.00000
         0           343.25000           164.20000          -180.00000
.END_PLACE_KEEPOUT
.PLACE_KEEPOUT      UNOWNED
BOTTOM 3.10000        
         0           403.35000           164.20000             0.00000
         0           410.85000           164.20000          -180.00000
         0           403.35000           164.20000          -180.00000
.END_PLACE_KEEPOUT
.PLACE_KEEPOUT      UNOWNED
BOTTOM 3.10000        
         0            39.00000           164.20000             0.00000
         0            46.50000           164.20000          -180.00000
         0            39.00000           164.20000          -180.00000
.END_PLACE_KEEPOUT
.PLACE_KEEPOUT      UNOWNED
BOTTOM 3.10000        
         0           163.95000           164.20000             0.00000
         0           171.45000           164.20000          -180.00000
         0           163.95000           164.20000          -180.00000
.END_PLACE_KEEPOUT
.PLACE_KEEPOUT      UNOWNED
BOTTOM 3.10000        
         0            87.82500           210.80000             0.00000
         0           167.82500           210.80000          -180.00000
         0            87.82500           210.80000          -180.00000
.END_PLACE_KEEPOUT
.PLACE_KEEPOUT      UNOWNED
BOTTOM 3.10000        
         0           385.17500           210.80000             0.00000
         0           465.17500           210.80000          -180.00000
         0           385.17500           210.80000          -180.00000
.END_PLACE_KEEPOUT
.ROUTE_KEEPOUT  UNOWNED
TOP
         0           152.32500            92.80000             0.00000
         0           166.32500            92.80000           180.00000
         0           166.32500            98.80000             0.00000
         0           152.32500            98.80000           180.00000
         0           152.32500            92.80000             0.00000
.END_ROUTE_KEEPOUT
.ROUTE_KEEPOUT  UNOWNED
TOP
         0            89.32500            92.80000             0.00000
         0           103.32500            92.80000           180.00000
         0           103.32500            98.80000             0.00000
         0            89.32500            98.80000           180.00000
         0            89.32500            92.80000             0.00000
.END_ROUTE_KEEPOUT
.ROUTE_KEEPOUT  UNOWNED
TOP
         0            26.32500            92.80000             0.00000
         0            40.32500            92.80000           180.00000
         0            40.32500            98.80000             0.00000
         0            26.32500            98.80000           180.00000
         0            26.32500            92.80000             0.00000
.END_ROUTE_KEEPOUT
.ROUTE_KEEPOUT  UNOWNED
TOP
         0           195.30000            63.80000             0.00000
         0           209.30000            63.80000           180.00000
         0           209.30000            69.80000             0.00000
         0           195.30000            69.80000           180.00000
         0           195.30000            63.80000             0.00000
.END_ROUTE_KEEPOUT
.ROUTE_KEEPOUT  UNOWNED
TOP
         0           323.67500            92.80000             0.00000
         0           337.67500            92.80000           180.00000
         0           337.67500            98.80000             0.00000
         0           323.67500            98.80000           180.00000
         0           323.67500            92.80000             0.00000
.END_ROUTE_KEEPOUT
.ROUTE_KEEPOUT  UNOWNED
TOP
         0           449.67500            92.80000             0.00000
         0           463.67500            92.80000           180.00000
         0           463.67500            98.80000             0.00000
         0           449.67500            98.80000           180.00000
         0           449.67500            92.80000             0.00000
.END_ROUTE_KEEPOUT
.ROUTE_KEEPOUT  UNOWNED
TOP
         0           386.67500            92.80000             0.00000
         0           400.67500            92.80000           180.00000
         0           400.67500            98.80000             0.00000
         0           386.67500            98.80000           180.00000
         0           386.67500            92.80000             0.00000
.END_ROUTE_KEEPOUT
.ROUTE_KEEPOUT  UNOWNED
TOP
         0           293.20000           138.20000             0.00000
         0           307.20000           138.20000           180.00000
         0           307.20000           144.20000             0.00000
         0           293.20000           144.20000           180.00000
         0           293.20000           138.20000             0.00000
.END_ROUTE_KEEPOUT
.ROUTE_KEEPOUT  UNOWNED
TOP
         0           195.30000           183.80000             0.00000
         0           209.30000           183.80000           180.00000
         0           209.30000           189.80000             0.00000
         0           195.30000           189.80000           180.00000
         0           195.30000           183.80000             0.00000
.END_ROUTE_KEEPOUT
.ROUTE_KEEPOUT  UNOWNED
TOP
         0           152.32500           207.80000             0.00000
         0           166.32500           207.80000           180.00000
         0           166.32500           213.80000             0.00000
         0           152.32500           213.80000           180.00000
         0           152.32500           207.80000             0.00000
.END_ROUTE_KEEPOUT
.ROUTE_KEEPOUT  UNOWNED
TOP
         0            89.32500           207.80000             0.00000
         0           103.32500           207.80000           180.00000
         0           103.32500           213.80000             0.00000
         0            89.32500           213.80000           180.00000
         0            89.32500           207.80000             0.00000
.END_ROUTE_KEEPOUT
.ROUTE_KEEPOUT  UNOWNED
TOP
         0            26.32500           207.80000             0.00000
         0            40.32500           207.80000           180.00000
         0            40.32500           213.80000             0.00000
         0            26.32500           213.80000           180.00000
         0            26.32500           207.80000             0.00000
.END_ROUTE_KEEPOUT
.ROUTE_KEEPOUT  UNOWNED
TOP
         0            26.32500           322.80000             0.00000
         0            40.32500           322.80000           180.00000
         0            40.32500           328.80000             0.00000
         0            26.32500           328.80000           180.00000
         0            26.32500           322.80000             0.00000
.END_ROUTE_KEEPOUT
.ROUTE_KEEPOUT  UNOWNED
TOP
         0            89.32500           322.80000             0.00000
         0           103.32500           322.80000           180.00000
         0           103.32500           328.80000             0.00000
         0            89.32500           328.80000           180.00000
         0            89.32500           322.80000             0.00000
.END_ROUTE_KEEPOUT
.ROUTE_KEEPOUT  UNOWNED
TOP
         0           152.32500           322.80000             0.00000
         0           166.32500           322.80000           180.00000
         0           166.32500           328.80000             0.00000
         0           152.32500           328.80000           180.00000
         0           152.32500           322.80000             0.00000
.END_ROUTE_KEEPOUT
.ROUTE_KEEPOUT  UNOWNED
TOP
         0           293.20000           243.20000             0.00000
         0           307.20000           243.20000           180.00000
         0           307.20000           249.20000             0.00000
         0           293.20000           249.20000           180.00000
         0           293.20000           243.20000             0.00000
.END_ROUTE_KEEPOUT
.ROUTE_KEEPOUT  UNOWNED
TOP
         0           237.20000           273.20000             0.00000
         0           251.20000           273.20000           180.00000
         0           251.20000           279.20000             0.00000
         0           237.20000           279.20000           180.00000
         0           237.20000           273.20000             0.00000
.END_ROUTE_KEEPOUT
.ROUTE_KEEPOUT  UNOWNED
TOP
         0           323.67500           207.80000             0.00000
         0           337.67500           207.80000           180.00000
         0           337.67500           213.80000             0.00000
         0           323.67500           213.80000           180.00000
         0           323.67500           207.80000             0.00000
.END_ROUTE_KEEPOUT
.ROUTE_KEEPOUT  UNOWNED
TOP
         0           386.67500           207.80000             0.00000
         0           400.67500           207.80000           180.00000
         0           400.67500           213.80000             0.00000
         0           386.67500           213.80000           180.00000
         0           386.67500           207.80000             0.00000
.END_ROUTE_KEEPOUT
.ROUTE_KEEPOUT  UNOWNED
TOP
         0           449.67500           207.80000             0.00000
         0           463.67500           207.80000           180.00000
         0           463.67500           213.80000             0.00000
         0           449.67500           213.80000           180.00000
         0           449.67500           207.80000             0.00000
.END_ROUTE_KEEPOUT
.ROUTE_KEEPOUT  UNOWNED
TOP
         0           449.67500           322.80000             0.00000
         0           463.67500           322.80000           180.00000
         0           463.67500           328.80000             0.00000
         0           449.67500           328.80000           180.00000
         0           449.67500           322.80000             0.00000
.END_ROUTE_KEEPOUT
.ROUTE_KEEPOUT  UNOWNED
TOP
         0           386.67500           322.80000             0.00000
         0           400.67500           322.80000           180.00000
         0           400.67500           328.80000             0.00000
         0           386.67500           328.80000           180.00000
         0           386.67500           322.80000             0.00000
.END_ROUTE_KEEPOUT
.ROUTE_KEEPOUT  UNOWNED
TOP
         0           323.67500           322.80000             0.00000
         0           337.67500           322.80000           180.00000
         0           337.67500           328.80000             0.00000
         0           323.67500           328.80000           180.00000
         0           323.67500           322.80000             0.00000
.END_ROUTE_KEEPOUT
.ROUTE_KEEPOUT  UNOWNED
TOP
         0           293.20000           393.20000             0.00000
         0           307.20000           393.20000           180.00000
         0           307.20000           399.20000             0.00000
         0           293.20000           399.20000           180.00000
         0           293.20000           393.20000             0.00000
.END_ROUTE_KEEPOUT
.ROUTE_KEEPOUT  UNOWNED
TOP
         0           237.20000           360.20000             0.00000
         0           251.20000           360.20000           180.00000
         0           251.20000           366.20000             0.00000
         0           237.20000           366.20000           180.00000
         0           237.20000           360.20000             0.00000
.END_ROUTE_KEEPOUT
.ROUTE_KEEPOUT  UNOWNED
TOP
         0           367.85000           220.20000             0.00000
         0           375.35000           220.20000           180.00000
         0           367.85000           220.20000           180.00000
.END_ROUTE_KEEPOUT
.ROUTE_KEEPOUT  UNOWNED
TOP
         0           178.65000           208.50000             0.00000
         0           186.15000           208.50000           180.00000
         0           178.65000           208.50000           180.00000
.END_ROUTE_KEEPOUT
.ROUTE_KEEPOUT  UNOWNED
TOP
         0           485.00000             5.50000             0.00000
         0           477.50000             5.50000           180.00000
         0           485.00000             5.50000           180.00000
.END_ROUTE_KEEPOUT
.ROUTE_KEEPOUT  UNOWNED
TOP
         0           485.00000           120.50000             0.00000
         0           477.50000           120.50000           180.00000
         0           485.00000           120.50000           180.00000
.END_ROUTE_KEEPOUT
.ROUTE_KEEPOUT  UNOWNED
TOP
         0           251.60000            -6.50000             0.00000
         0           244.10000            -6.50000           180.00000
         0           251.60000            -6.50000           180.00000
.END_ROUTE_KEEPOUT
.ROUTE_KEEPOUT  UNOWNED
TOP
         0           251.60000           143.50000             0.00000
         0           244.10000           143.50000           180.00000
         0           251.60000           143.50000           180.00000
.END_ROUTE_KEEPOUT
.ROUTE_KEEPOUT  UNOWNED
TOP
         0             7.60000             5.50000             0.00000
         0             0.10000             5.50000           180.00000
         0             7.60000             5.50000           180.00000
.END_ROUTE_KEEPOUT
.ROUTE_KEEPOUT  UNOWNED
TOP
         0             7.60000           120.50000             0.00000
         0             0.10000           120.50000           180.00000
         0             7.60000           120.50000           180.00000
.END_ROUTE_KEEPOUT
.ROUTE_KEEPOUT  UNOWNED
TOP
         0           411.17500           210.80000             0.00000
         0           439.17500           210.80000           180.00000
         0           411.17500           210.80000           180.00000
.END_ROUTE_KEEPOUT
.ROUTE_KEEPOUT  UNOWNED
TOP
         0           113.82500           210.80000             0.00000
         0           141.82500           210.80000           180.00000
         0           113.82500           210.80000           180.00000
.END_ROUTE_KEEPOUT
.ROUTE_KEEPOUT  UNOWNED
TOP
         0           369.15000            28.08000             0.00000
         0           375.15000            28.08000           180.00000
         0           369.15000            28.08000           180.00000
.END_ROUTE_KEEPOUT
.ROUTE_KEEPOUT  UNOWNED
TOP
         0           226.10000            -6.50000             0.00000
         0           233.60000            -6.50000           180.00000
         0           226.10000            -6.50000           180.00000
.END_ROUTE_KEEPOUT
.ROUTE_KEEPOUT  UNOWNED
TOP
         0           123.15000            28.08000             0.00000
         0           129.15000            28.08000           180.00000
         0           123.15000            28.08000           180.00000
.END_ROUTE_KEEPOUT
.ROUTE_KEEPOUT  UNOWNED
TOP
         0           226.10000           143.50000             0.00000
         0           233.60000           143.50000           180.00000
         0           226.10000           143.50000           180.00000
.END_ROUTE_KEEPOUT
.ROUTE_KEEPOUT  UNOWNED
TOP
         0           165.45000           270.00000             0.00000
         0           174.95000           270.00000           180.00000
         0           165.45000           270.00000           180.00000
.END_ROUTE_KEEPOUT
.ROUTE_KEEPOUT  UNOWNED
TOP
         0           111.85000           290.00000             0.00000
         0           102.35000           290.00000           180.00000
         0           111.85000           290.00000           180.00000
.END_ROUTE_KEEPOUT
.ROUTE_KEEPOUT  UNOWNED
TOP
         0            48.75000           270.00000             0.00000
         0            39.25000           270.00000           180.00000
         0            48.75000           270.00000           180.00000
.END_ROUTE_KEEPOUT
.ROUTE_KEEPOUT  UNOWNED
TOP
         0           472.25000           270.00000             0.00000
         0           462.75000           270.00000           180.00000
         0           472.25000           270.00000           180.00000
.END_ROUTE_KEEPOUT
.ROUTE_KEEPOUT  UNOWNED
TOP
         0           409.15000           290.00000             0.00000
         0           399.65000           290.00000           180.00000
         0           409.15000           290.00000           180.00000
.END_ROUTE_KEEPOUT
.ROUTE_KEEPOUT  UNOWNED
TOP
         0           346.05000           270.00000             0.00000
         0           336.55000           270.00000           180.00000
         0           346.05000           270.00000           180.00000
.END_ROUTE_KEEPOUT
.ROUTE_KEEPOUT  UNOWNED
TOP
         0           284.30000           414.22000             0.00000
         0           276.80000           414.22000           180.00000
         0           284.30000           414.22000           180.00000
.END_ROUTE_KEEPOUT
.ROUTE_KEEPOUT  UNOWNED
TOP
         0             4.25000           224.20000             0.00000
         0            11.75000           224.20000           180.00000
         0             4.25000           224.20000           180.00000
.END_ROUTE_KEEPOUT
.ROUTE_KEEPOUT  UNOWNED
TOP
         0           479.70000           204.20000             0.00000
         0           487.20000           204.20000           180.00000
         0           479.70000           204.20000           180.00000
.END_ROUTE_KEEPOUT
.ROUTE_KEEPOUT  UNOWNED
TOP
         0           403.35000           164.20000             0.00000
         0           410.85000           164.20000           180.00000
         0           403.35000           164.20000           180.00000
.END_ROUTE_KEEPOUT
.ROUTE_KEEPOUT  UNOWNED
TOP
         0           343.25000           164.20000             0.00000
         0           350.75000           164.20000           180.00000
         0           343.25000           164.20000           180.00000
.END_ROUTE_KEEPOUT
.ROUTE_KEEPOUT  UNOWNED
TOP
         0            39.00000           164.20000             0.00000
         0            46.50000           164.20000           180.00000
         0            39.00000           164.20000           180.00000
.END_ROUTE_KEEPOUT
.ROUTE_KEEPOUT  UNOWNED
TOP
         0           163.95000           164.20000             0.00000
         0           171.45000           164.20000           180.00000
         0           163.95000           164.20000           180.00000
.END_ROUTE_KEEPOUT
.ROUTE_KEEPOUT  UNOWNED
TOP
         0           233.50000           -11.80000             0.00000
         0           233.50000           -17.80000             0.00000
         0           246.50000           -17.80000           180.00000
         0           246.50000           -11.80000             0.00000
         0           246.20717            -9.87099            17.26371
         0           244.10000            -6.50000           -64.01802
         0           244.10929            -6.76376             4.03322
         0           233.50000           -11.80000           129.21247
.END_ROUTE_KEEPOUT
.ROUTE_KEEPOUT  UNOWNED
BOTTOM
         0           293.20000           393.20000             0.00000
         0           293.20000           399.20000             0.00000
         0           307.20000           399.20000          -180.00000
         0           307.20000           393.20000             0.00000
         0           293.20000           393.20000          -180.00000
.END_ROUTE_KEEPOUT
.ROUTE_KEEPOUT  UNOWNED
BOTTOM
         0           323.67500           322.80000             0.00000
         0           323.67500           328.80000             0.00000
         0           337.67500           328.80000          -180.00000
         0           337.67500           322.80000             0.00000
         0           323.67500           322.80000          -180.00000
.END_ROUTE_KEEPOUT
.ROUTE_KEEPOUT  UNOWNED
BOTTOM
         0           237.20000           360.20000             0.00000
         0           237.20000           366.20000             0.00000
         0           251.20000           366.20000          -180.00000
         0           251.20000           360.20000             0.00000
         0           237.20000           360.20000          -180.00000
.END_ROUTE_KEEPOUT
.ROUTE_KEEPOUT  UNOWNED
BOTTOM
         0           152.32500           322.80000             0.00000
         0           152.32500           328.80000             0.00000
         0           166.32500           328.80000          -180.00000
         0           166.32500           322.80000             0.00000
         0           152.32500           322.80000          -180.00000
.END_ROUTE_KEEPOUT
.ROUTE_KEEPOUT  UNOWNED
BOTTOM
         0            89.32500           322.80000             0.00000
         0            89.32500           328.80000             0.00000
         0           103.32500           328.80000          -180.00000
         0           103.32500           322.80000             0.00000
         0            89.32500           322.80000          -180.00000
.END_ROUTE_KEEPOUT
.ROUTE_KEEPOUT  UNOWNED
BOTTOM
         0            26.32500           322.80000             0.00000
         0            26.32500           328.80000             0.00000
         0            40.32500           328.80000          -180.00000
         0            40.32500           322.80000             0.00000
         0            26.32500           322.80000          -180.00000
.END_ROUTE_KEEPOUT
.ROUTE_KEEPOUT  UNOWNED
BOTTOM
         0           237.20000           273.20000             0.00000
         0           237.20000           279.20000             0.00000
         0           251.20000           279.20000          -180.00000
         0           251.20000           273.20000             0.00000
         0           237.20000           273.20000          -180.00000
.END_ROUTE_KEEPOUT
.ROUTE_KEEPOUT  UNOWNED
BOTTOM
         0           449.67500           322.80000             0.00000
         0           449.67500           328.80000             0.00000
         0           463.67500           328.80000          -180.00000
         0           463.67500           322.80000             0.00000
         0           449.67500           322.80000          -180.00000
.END_ROUTE_KEEPOUT
.ROUTE_KEEPOUT  UNOWNED
BOTTOM
         0           386.67500           322.80000             0.00000
         0           386.67500           328.80000             0.00000
         0           400.67500           328.80000          -180.00000
         0           400.67500           322.80000             0.00000
         0           386.67500           322.80000          -180.00000
.END_ROUTE_KEEPOUT
.ROUTE_KEEPOUT  UNOWNED
BOTTOM
         0           449.67500           207.80000             0.00000
         0           449.67500           213.80000             0.00000
         0           463.67500           213.80000          -180.00000
         0           463.67500           207.80000             0.00000
         0           449.67500           207.80000          -180.00000
.END_ROUTE_KEEPOUT
.ROUTE_KEEPOUT  UNOWNED
BOTTOM
         0           386.67500           207.80000             0.00000
         0           386.67500           213.80000             0.00000
         0           400.67500           213.80000          -180.00000
         0           400.67500           207.80000             0.00000
         0           386.67500           207.80000          -180.00000
.END_ROUTE_KEEPOUT
.ROUTE_KEEPOUT  UNOWNED
BOTTOM
         0           323.67500           207.80000             0.00000
         0           323.67500           213.80000             0.00000
         0           337.67500           213.80000          -180.00000
         0           337.67500           207.80000             0.00000
         0           323.67500           207.80000          -180.00000
.END_ROUTE_KEEPOUT
.ROUTE_KEEPOUT  UNOWNED
BOTTOM
         0           293.20000           243.20000             0.00000
         0           293.20000           249.20000             0.00000
         0           307.20000           249.20000          -180.00000
         0           307.20000           243.20000             0.00000
         0           293.20000           243.20000          -180.00000
.END_ROUTE_KEEPOUT
.ROUTE_KEEPOUT  UNOWNED
BOTTOM
         0           195.30000           183.80000             0.00000
         0           195.30000           189.80000             0.00000
         0           209.30000           189.80000          -180.00000
         0           209.30000           183.80000             0.00000
         0           195.30000           183.80000          -180.00000
.END_ROUTE_KEEPOUT
.ROUTE_KEEPOUT  UNOWNED
BOTTOM
         0           152.32500           207.80000             0.00000
         0           152.32500           213.80000             0.00000
         0           166.32500           213.80000          -180.00000
         0           166.32500           207.80000             0.00000
         0           152.32500           207.80000          -180.00000
.END_ROUTE_KEEPOUT
.ROUTE_KEEPOUT  UNOWNED
BOTTOM
         0            89.32500           207.80000             0.00000
         0            89.32500           213.80000             0.00000
         0           103.32500           213.80000          -180.00000
         0           103.32500           207.80000             0.00000
         0            89.32500           207.80000          -180.00000
.END_ROUTE_KEEPOUT
.ROUTE_KEEPOUT  UNOWNED
BOTTOM
         0            26.32500           207.80000             0.00000
         0            26.32500           213.80000             0.00000
         0            40.32500           213.80000          -180.00000
         0            40.32500           207.80000             0.00000
         0            26.32500           207.80000          -180.00000
.END_ROUTE_KEEPOUT
.ROUTE_KEEPOUT  UNOWNED
BOTTOM
         0            26.32500            92.80000             0.00000
         0            26.32500            98.80000             0.00000
         0            40.32500            98.80000          -180.00000
         0            40.32500            92.80000             0.00000
         0            26.32500            92.80000          -180.00000
.END_ROUTE_KEEPOUT
.ROUTE_KEEPOUT  UNOWNED
BOTTOM
         0            89.32500            92.80000             0.00000
         0            89.32500            98.80000             0.00000
         0           103.32500            98.80000          -180.00000
         0           103.32500            92.80000             0.00000
         0            89.32500            92.80000          -180.00000
.END_ROUTE_KEEPOUT
.ROUTE_KEEPOUT  UNOWNED
BOTTOM
         0           152.32500            92.80000             0.00000
         0           152.32500            98.80000             0.00000
         0           166.32500            98.80000          -180.00000
         0           166.32500            92.80000             0.00000
         0           152.32500            92.80000          -180.00000
.END_ROUTE_KEEPOUT
.ROUTE_KEEPOUT  UNOWNED
BOTTOM
         0           195.30000            63.80000             0.00000
         0           195.30000            69.80000             0.00000
         0           209.30000            69.80000          -180.00000
         0           209.30000            63.80000             0.00000
         0           195.30000            63.80000          -180.00000
.END_ROUTE_KEEPOUT
.ROUTE_KEEPOUT  UNOWNED
BOTTOM
         0           293.20000           138.20000             0.00000
         0           293.20000           144.20000             0.00000
         0           307.20000           144.20000          -180.00000
         0           307.20000           138.20000             0.00000
         0           293.20000           138.20000          -180.00000
.END_ROUTE_KEEPOUT
.ROUTE_KEEPOUT  UNOWNED
BOTTOM
         0           323.67500            92.80000             0.00000
         0           323.67500            98.80000             0.00000
         0           337.67500            98.80000          -180.00000
         0           337.67500            92.80000             0.00000
         0           323.67500            92.80000          -180.00000
.END_ROUTE_KEEPOUT
.ROUTE_KEEPOUT  UNOWNED
BOTTOM
         0           449.67500            92.80000             0.00000
         0           449.67500            98.80000             0.00000
         0           463.67500            98.80000          -180.00000
         0           463.67500            92.80000             0.00000
         0           449.67500            92.80000          -180.00000
.END_ROUTE_KEEPOUT
.ROUTE_KEEPOUT  UNOWNED
BOTTOM
         0           386.67500            92.80000             0.00000
         0           386.67500            98.80000             0.00000
         0           400.67500            98.80000          -180.00000
         0           400.67500            92.80000             0.00000
         0           386.67500            92.80000          -180.00000
.END_ROUTE_KEEPOUT
.ROUTE_KEEPOUT  UNOWNED
BOTTOM
         0           178.65000           208.50000             0.00000
         0           186.15000           208.50000          -180.00000
         0           178.65000           208.50000          -180.00000
.END_ROUTE_KEEPOUT
.ROUTE_KEEPOUT  UNOWNED
BOTTOM
         0           367.85000           220.20000             0.00000
         0           375.35000           220.20000          -180.00000
         0           367.85000           220.20000          -180.00000
.END_ROUTE_KEEPOUT
.ROUTE_KEEPOUT  UNOWNED
BOTTOM
         0           439.17500           210.80000             0.00000
         0           411.17500           210.80000          -180.00000
         0           439.17500           210.80000          -180.00000
.END_ROUTE_KEEPOUT
.ROUTE_KEEPOUT  UNOWNED
BOTTOM
         0           141.82500           210.80000             0.00000
         0           113.82500           210.80000          -180.00000
         0           141.82500           210.80000          -180.00000
.END_ROUTE_KEEPOUT
.ROUTE_KEEPOUT  UNOWNED
BOTTOM
         0           161.57500             9.20000             0.00000
         0           171.07500             9.20000          -180.00000
         0           161.57500             9.20000          -180.00000
.END_ROUTE_KEEPOUT
.ROUTE_KEEPOUT  UNOWNED
BOTTOM
         0            31.07500             9.20000             0.00000
         0            21.57500             9.20000          -180.00000
         0            31.07500             9.20000          -180.00000
.END_ROUTE_KEEPOUT
.ROUTE_KEEPOUT  UNOWNED
BOTTOM
         0             7.60000             5.50000             0.00000
         0             0.10000             5.50000          -180.00000
         0             7.60000             5.50000          -180.00000
.END_ROUTE_KEEPOUT
.ROUTE_KEEPOUT  UNOWNED
BOTTOM
         0             7.60000           120.50000             0.00000
         0             0.10000           120.50000          -180.00000
         0             7.60000           120.50000          -180.00000
.END_ROUTE_KEEPOUT
.ROUTE_KEEPOUT  UNOWNED
BOTTOM
         0           328.42500             9.20000             0.00000
         0           318.92500             9.20000          -180.00000
         0           328.42500             9.20000          -180.00000
.END_ROUTE_KEEPOUT
.ROUTE_KEEPOUT  UNOWNED
BOTTOM
         0           468.42500             9.20000             0.00000
         0           458.92500             9.20000          -180.00000
         0           468.42500             9.20000          -180.00000
.END_ROUTE_KEEPOUT
.ROUTE_KEEPOUT  UNOWNED
BOTTOM
         0           485.00000             5.50000             0.00000
         0           477.50000             5.50000          -180.00000
         0           485.00000             5.50000          -180.00000
.END_ROUTE_KEEPOUT
.ROUTE_KEEPOUT  UNOWNED
BOTTOM
         0           485.00000           120.50000             0.00000
         0           477.50000           120.50000          -180.00000
         0           485.00000           120.50000          -180.00000
.END_ROUTE_KEEPOUT
.ROUTE_KEEPOUT  UNOWNED
BOTTOM
         0           251.60000            -6.50000             0.00000
         0           244.10000            -6.50000          -180.00000
         0           251.60000            -6.50000          -180.00000
.END_ROUTE_KEEPOUT
.ROUTE_KEEPOUT  UNOWNED
BOTTOM
         0           233.60000            -6.50000             0.00000
         0           226.10000            -6.50000          -180.00000
         0           233.60000            -6.50000          -180.00000
.END_ROUTE_KEEPOUT
.ROUTE_KEEPOUT  UNOWNED
BOTTOM
         0           251.60000           143.50000             0.00000
         0           244.10000           143.50000          -180.00000
         0           251.60000           143.50000          -180.00000
.END_ROUTE_KEEPOUT
.ROUTE_KEEPOUT  UNOWNED
BOTTOM
         0           233.60000           143.50000             0.00000
         0           226.10000           143.50000          -180.00000
         0           233.60000           143.50000          -180.00000
.END_ROUTE_KEEPOUT
.ROUTE_KEEPOUT  UNOWNED
BOTTOM
         0           174.95000           270.00000             0.00000
         0           165.45000           270.00000          -180.00000
         0           174.95000           270.00000          -180.00000
.END_ROUTE_KEEPOUT
.ROUTE_KEEPOUT  UNOWNED
BOTTOM
         0           111.85000           290.00000             0.00000
         0           102.35000           290.00000          -180.00000
         0           111.85000           290.00000          -180.00000
.END_ROUTE_KEEPOUT
.ROUTE_KEEPOUT  UNOWNED
BOTTOM
         0            48.75000           270.00000             0.00000
         0            39.25000           270.00000          -180.00000
         0            48.75000           270.00000          -180.00000
.END_ROUTE_KEEPOUT
.ROUTE_KEEPOUT  UNOWNED
BOTTOM
         0           472.25000           270.00000             0.00000
         0           462.75000           270.00000          -180.00000
         0           472.25000           270.00000          -180.00000
.END_ROUTE_KEEPOUT
.ROUTE_KEEPOUT  UNOWNED
BOTTOM
         0           409.15000           290.00000             0.00000
         0           399.65000           290.00000          -180.00000
         0           409.15000           290.00000          -180.00000
.END_ROUTE_KEEPOUT
.ROUTE_KEEPOUT  UNOWNED
BOTTOM
         0           346.05000           270.00000             0.00000
         0           336.55000           270.00000          -180.00000
         0           346.05000           270.00000          -180.00000
.END_ROUTE_KEEPOUT
.ROUTE_KEEPOUT  UNOWNED
BOTTOM
         0           284.30000           414.22000             0.00000
         0           276.80000           414.22000          -180.00000
         0           284.30000           414.22000          -180.00000
.END_ROUTE_KEEPOUT
.ROUTE_KEEPOUT  UNOWNED
BOTTOM
         0           410.85000           164.20000             0.00000
         0           403.35000           164.20000          -180.00000
         0           410.85000           164.20000          -180.00000
.END_ROUTE_KEEPOUT
.ROUTE_KEEPOUT  UNOWNED
BOTTOM
         0           350.75000           164.20000             0.00000
         0           343.25000           164.20000          -180.00000
         0           350.75000           164.20000          -180.00000
.END_ROUTE_KEEPOUT
.ROUTE_KEEPOUT  UNOWNED
BOTTOM
         0           171.45000           164.20000             0.00000
         0           163.95000           164.20000          -180.00000
         0           171.45000           164.20000          -180.00000
.END_ROUTE_KEEPOUT
.ROUTE_KEEPOUT  UNOWNED
BOTTOM
         0            46.50000           164.20000             0.00000
         0            39.00000           164.20000          -180.00000
         0            46.50000           164.20000          -180.00000
.END_ROUTE_KEEPOUT
.ROUTE_KEEPOUT  UNOWNED
BOTTOM
         0            11.75000           224.20000             0.00000
         0             4.25000           224.20000          -180.00000
         0            11.75000           224.20000          -180.00000
.END_ROUTE_KEEPOUT
.ROUTE_KEEPOUT  UNOWNED
BOTTOM
         0           487.20000           204.20000             0.00000
         0           479.70000           204.20000          -180.00000
         0           487.20000           204.20000          -180.00000
.END_ROUTE_KEEPOUT
.PLACEMENT
020_50215_0164 020_50215_0164 MONO2         
239.30000      14.85000       0.00000        90.00000       TOP       PLACED         
020_50215_0164 020_50215_0164 MONO4         
282.00000      14.85000       0.00000        90.00000       TOP       PLACED         
020_50215_0164 020_50215_0164 MONO1         
239.30000      111.15000      0.00000        90.00000       TOP       PLACED         
020_50215_0164 020_50215_0164 MONO3         
282.00000      111.15000      0.00000        90.00000       TOP       PLACED         
062_10010_0121 062_10010_0121 HDDSAS35      
483.30000      57.91000       0.00000        270.00000      TOP       PLACED         
062_10010_0121 062_10010_0121 HDDSAS34      
451.75000      57.91000       0.00000        270.00000      TOP       PLACED         
062_10010_0121 062_10010_0121 HDDSAS33      
420.20000      57.91000       0.00000        270.00000      TOP       PLACED         
062_10010_0121 062_10010_0121 HDDSAS32      
388.65000      57.91000       0.00000        270.00000      TOP       PLACED         
062_10010_0121 062_10010_0121 HDDSAS31      
357.10000      57.91000       0.00000        270.00000      TOP       PLACED         
062_10010_0121 062_10010_0121 HDDSAS30      
325.55000      57.91000       0.00000        270.00000      TOP       PLACED         
062_10010_0121 062_10010_0121 HDDSAS23      
483.30000      172.91000      0.00000        270.00000      TOP       PLACED         
062_10010_0121 062_10010_0121 HDDSAS22      
451.75000      172.91000      0.00000        270.00000      TOP       PLACED         
062_10010_0121 062_10010_0121 HDDSAS21      
420.20000      172.91000      0.00000        270.00000      TOP       PLACED         
062_10010_0121 062_10010_0121 HDDSAS20      
388.65000      172.91000      0.00000        270.00000      TOP       PLACED         
062_10010_0121 062_10010_0121 HDDSAS19      
357.10000      172.91000      0.00000        270.00000      TOP       PLACED         
062_10010_0121 062_10010_0121 HDDSAS18      
325.55000      172.91000      0.00000        270.00000      TOP       PLACED         
062_10010_0121 062_10010_0121 HDDSAS11      
483.30000      287.91000      0.00000        270.00000      TOP       PLACED         
062_10010_0121 062_10010_0121 HDDSAS10      
451.75000      287.91000      0.00000        270.00000      TOP       PLACED         
062_10010_0121 062_10010_0121 HDDSAS9       
420.20000      287.91000      0.00000        270.00000      TOP       PLACED         
062_10010_0121 062_10010_0121 HDDSAS8       
388.65000      287.91000      0.00000        270.00000      TOP       PLACED         
062_10010_0121 062_10010_0121 HDDSAS7       
357.10000      287.91000      0.00000        270.00000      TOP       PLACED         
062_10010_0121 062_10010_0121 HDDSAS6       
325.55000      287.91000      0.00000        270.00000      TOP       PLACED         
062_10010_0121 062_10010_0121 HDDSAS29      
185.95000      57.91000       0.00000        270.00000      TOP       PLACED         
062_10010_0121 062_10010_0121 HDDSAS28      
154.40000      57.91000       0.00000        270.00000      TOP       PLACED         
062_10010_0121 062_10010_0121 HDDSAS27      
122.85000      57.91000       0.00000        270.00000      TOP       PLACED         
062_10010_0121 062_10010_0121 HDDSAS26      
91.30000       57.91000       0.00000        270.00000      TOP       PLACED         
062_10010_0121 062_10010_0121 HDDSAS25      
59.75000       57.91000       0.00000        270.00000      TOP       PLACED         
062_10010_0121 062_10010_0121 HDDSAS24      
28.20000       57.91000       0.00000        270.00000      TOP       PLACED         
062_10010_0121 062_10010_0121 HDDSAS17      
185.95000      172.91000      0.00000        270.00000      TOP       PLACED         
062_10010_0121 062_10010_0121 HDDSAS16      
154.40000      172.91000      0.00000        270.00000      TOP       PLACED         
062_10010_0121 062_10010_0121 HDDSAS15      
122.85000      172.91000      0.00000        270.00000      TOP       PLACED         
062_10010_0121 062_10010_0121 HDDSAS14      
91.30000       172.91000      0.00000        270.00000      TOP       PLACED         
062_10010_0121 062_10010_0121 HDDSAS13      
59.75000       172.91000      0.00000        270.00000      TOP       PLACED         
062_10010_0121 062_10010_0121 HDDSAS12      
28.20000       172.91000      0.00000        270.00000      TOP       PLACED         
062_10010_0121 062_10010_0121 HDDSAS5       
185.95000      287.91000      0.00000        270.00000      TOP       PLACED         
062_10010_0121 062_10010_0121 HDDSAS4       
154.40000      287.91000      0.00000        270.00000      TOP       PLACED         
062_10010_0121 062_10010_0121 HDDSAS3       
122.85000      287.91000      0.00000        270.00000      TOP       PLACED         
062_10010_0121 062_10010_0121 HDDSAS2       
91.30000       287.91000      0.00000        270.00000      TOP       PLACED         
062_10010_0121 062_10010_0121 HDDSAS1       
59.75000       287.91000      0.00000        270.00000      TOP       PLACED         
062_10010_0121 062_10010_0121 HDDSAS0       
28.20000       287.91000      0.00000        270.00000      TOP       PLACED         
083_00195_0B70 083_00195_0B70 FLED18        
175.55000      94.40000       0.00000        0.00000        TOP       PLACED         
083_00195_0B70 083_00195_0B70 FLED17        
144.00000      94.40000       0.00000        0.00000        TOP       PLACED         
083_00195_0B70 083_00195_0B70 FLED16        
112.45000      94.40000       0.00000        0.00000        TOP       PLACED         
083_00195_0B70 083_00195_0B70 FLED15        
80.90000       94.40000       0.00000        0.00000        TOP       PLACED         
083_00195_0B70 083_00195_0B70 FLED14        
49.35000       94.40000       0.00000        0.00000        TOP       PLACED         
083_00195_0B70 083_00195_0B70 FLED13        
17.80000       94.40000       0.00000        0.00000        TOP       PLACED         
083_00195_0B70 083_00195_0B70 FLED6         
175.55000      209.40000      0.00000        0.00000        TOP       PLACED         
083_00195_0B70 083_00195_0B70 FLED5         
144.00000      209.40000      0.00000        0.00000        TOP       PLACED         
083_00195_0B70 083_00195_0B70 FLED4         
112.45000      209.40000      0.00000        0.00000        TOP       PLACED         
083_00195_0B70 083_00195_0B70 FLED3         
80.90000       209.40000      0.00000        0.00000        TOP       PLACED         
083_00195_0B70 083_00195_0B70 FLED2         
49.35000       209.40000      0.00000        0.00000        TOP       PLACED         
083_00195_0B70 083_00195_0B70 FLED1         
17.80000       209.40000      0.00000        0.00000        TOP       PLACED         
083_00195_0B70 083_00195_0B70 RLED30        
175.55000      324.40000      0.00000        0.00000        TOP       PLACED         
083_00195_0B70 083_00195_0B70 RLED29        
144.00000      324.40000      0.00000        0.00000        TOP       PLACED         
083_00195_0B70 083_00195_0B70 RLED28        
112.45000      324.40000      0.00000        0.00000        TOP       PLACED         
083_00195_0B70 083_00195_0B70 RLED27        
80.90000       324.40000      0.00000        0.00000        TOP       PLACED         
083_00195_0B70 083_00195_0B70 RLED26        
49.35000       324.40000      0.00000        0.00000        TOP       PLACED         
083_00195_0B70 083_00195_0B70 RLED25        
17.80000       324.40000      0.00000        0.00000        TOP       PLACED         
083_00195_0B70 083_00195_0B70 FLED24        
472.90000      94.40000       0.00000        0.00000        TOP       PLACED         
083_00195_0B70 083_00195_0B70 FLED23        
441.35000      94.40000       0.00000        0.00000        TOP       PLACED         
083_00195_0B70 083_00195_0B70 FLED22        
409.80000      94.40000       0.00000        0.00000        TOP       PLACED         
083_00195_0B70 083_00195_0B70 FLED21        
378.25000      94.40000       0.00000        0.00000        TOP       PLACED         
083_00195_0B70 083_00195_0B70 FLED20        
346.70000      94.40000       0.00000        0.00000        TOP       PLACED         
083_00195_0B70 083_00195_0B70 FLED19        
315.15000      94.40000       0.00000        0.00000        TOP       PLACED         
083_00195_0B70 083_00195_0B70 FLED12        
472.90000      209.40000      0.00000        0.00000        TOP       PLACED         
083_00195_0B70 083_00195_0B70 FLED11        
441.35000      209.40000      0.00000        0.00000        TOP       PLACED         
083_00195_0B70 083_00195_0B70 FLED10        
409.80000      209.40000      0.00000        0.00000        TOP       PLACED         
083_00195_0B70 083_00195_0B70 FLED9         
378.25000      209.40000      0.00000        0.00000        TOP       PLACED         
083_00195_0B70 083_00195_0B70 FLED8         
346.70000      209.40000      0.00000        0.00000        TOP       PLACED         
083_00195_0B70 083_00195_0B70 FLED7         
315.15000      209.40000      0.00000        0.00000        TOP       PLACED         
083_00195_0B70 083_00195_0B70 RLED36        
472.90000      324.40000      0.00000        0.00000        TOP       PLACED         
083_00195_0B70 083_00195_0B70 RLED35        
441.35000      324.40000      0.00000        0.00000        TOP       PLACED         
083_00195_0B70 083_00195_0B70 RLED34        
409.80000      324.40000      0.00000        0.00000        TOP       PLACED         
083_00195_0B70 083_00195_0B70 RLED33        
378.25000      324.40000      0.00000        0.00000        TOP       PLACED         
083_00195_0B70 083_00195_0B70 RLED32        
346.70000      324.40000      0.00000        0.00000        TOP       PLACED         
083_00195_0B70 083_00195_0B70 RLED31        
315.15000      324.40000      0.00000        0.00000        TOP       PLACED         
020_80656_0001 020_80656_0001 DPB2          
265.00000      418.67000      0.00000        180.00000      TOP       PLACED         
020_80959_0001 020_80959_0001 DPB1          
210.00000      419.20000      0.00000        0.00000        TOP       PLACED         
ZZ_80960_000101 ZZ_80960_000101 IO1           
143.35000      30.55000       -0.00000       180.00000      BOTTOM    PLACED         
ZZ_80960_000101 ZZ_80960_000101 IO2           
389.35000      30.55000       -0.00000       180.00000      BOTTOM    PLACED         
ZZ_PAD01_T21   ZZ_PAD01_T21   PWR1          
286.10000      406.70000      0.00000        270.00000      TOP       PLACED         
ZZ_00PAD_PN1   ZZ_00PAD_PN1   SAS1          
287.83660      357.70520      0.00000        270.00000      TOP       PLACED         
ZZ_00PAD_PS1   ZZ_00PAD_PS1   PCIE1         
287.83660      263.70220      0.00000        270.00000      TOP       PLACED         
062_10010_0121 062_10010_0121 IO3           
260.15000      -29.25000      0.00000        180.00000      TOP       PLACED         
020_F0496_0040 020_F0496_0040 LED1          
213.30000      4.50000        0.04596        0.00000        TOP       PLACED         
087_71242_0465 087_71242_0465 NUT1          
8.00000        224.20000      0.00000        180.00000      BOTTOM    PLACED         
087_71242_0465 087_71242_0465 NUT2          
483.45000      204.20000      0.00000        180.00000      BOTTOM    PLACED         
087_71242_0465 087_71242_0465 NUT3          
42.75000       164.20000      0.00000        180.00000      BOTTOM    PLACED         
087_71242_0465 087_71242_0465 NUT4          
167.70000      164.20000      0.00000        180.00000      BOTTOM    PLACED         
087_71242_0465 087_71242_0465 NUT5          
347.00000      164.20000      0.00000        180.00000      BOTTOM    PLACED         
087_71242_0465 087_71242_0465 NUT6          
407.10000      164.20000      0.00000        180.00000      BOTTOM    PLACED         
087_71242_0465 087_71242_0465 NUT7          
182.40000      208.50000      0.00000        180.00000      BOTTOM    PLACED         
087_71242_0465 087_71242_0465 NUT8          
371.60000      220.20000      0.00000        180.00000      BOTTOM    PLACED         
086_000IZ_0543 086_000IZ_0543 SCW1          
127.82500      210.80000      -0.00000       180.00000      BOTTOM    PLACED         
086_000IZ_0543 086_000IZ_0543 SCW2          
425.17500      210.80000      -0.00000       180.00000      BOTTOM    PLACED                 
.END_PLACEMENT
